G04*
G04 #@! TF.GenerationSoftware,Altium Limited,Altium Designer,22.4.2 (48)*
G04*
G04 Layer_Color=65535*
%FSLAX25Y25*%
%MOIN*%
G70*
G04*
G04 #@! TF.SameCoordinates,446674BB-F454-490D-8607-5140536C8ADF*
G04*
G04*
G04 #@! TF.FilePolarity,Positive*
G04*
G01*
G75*
%ADD10C,0.01000*%
%ADD11C,0.00984*%
%ADD12C,0.01575*%
%ADD13C,0.00787*%
%ADD14C,0.00394*%
%ADD15C,0.01575*%
%ADD16C,0.00472*%
%ADD17C,0.00600*%
%ADD18C,0.00800*%
%ADD19C,0.00799*%
%ADD20C,0.00591*%
%ADD21C,0.00500*%
%ADD22C,0.00900*%
%ADD23R,0.50197X0.35236*%
%ADD24R,0.17717X0.59055*%
%ADD25R,0.29528X0.28543*%
D10*
X288354Y-227593D02*
G03*
X288354Y-227593I-500J0D01*
G01*
D02*
G03*
X288354Y-227593I-500J0D01*
G01*
X122441Y-336614D02*
Y-136614D01*
X322441D01*
Y-336614D02*
Y-136614D01*
X122441Y-336614D02*
X322441D01*
X608193Y-198819D02*
Y-148425D01*
X555587D02*
X608193D01*
X555587Y-198819D02*
Y-148425D01*
Y-198819D02*
X608193D01*
X572616Y-300102D02*
X625222D01*
X572616D02*
Y-249709D01*
X625222D01*
Y-300102D02*
Y-249709D01*
X664695Y-106427D02*
Y18573D01*
X400207D02*
X664695D01*
X400207Y-106427D02*
Y18573D01*
Y-106427D02*
X664695D01*
X58730Y-106269D02*
Y18731D01*
Y-106269D02*
X323218D01*
Y18731D01*
X58730D02*
X323218D01*
X38293Y-71625D02*
X37293Y-72625D01*
Y-74624D01*
X38293Y-75624D01*
X42292D01*
X43291Y-74624D01*
Y-72625D01*
X42292Y-71625D01*
X40292D01*
Y-73624D01*
X43291Y-69626D02*
X37293D01*
X43291Y-65627D01*
X37293D01*
X38293Y-59629D02*
X37293Y-60628D01*
Y-62628D01*
X38293Y-63627D01*
X39293D01*
X40292Y-62628D01*
Y-60628D01*
X41292Y-59629D01*
X42292D01*
X43291Y-60628D01*
Y-62628D01*
X42292Y-63627D01*
X38293Y-53631D02*
X37293Y-54630D01*
Y-56630D01*
X38293Y-57629D01*
X39293D01*
X40292Y-56630D01*
Y-54630D01*
X41292Y-53631D01*
X42292D01*
X43291Y-54630D01*
Y-56630D01*
X42292Y-57629D01*
X43291Y-51631D02*
Y-49632D01*
Y-50632D01*
X37293D01*
X38293Y-51631D01*
X38293Y-117885D02*
X37293Y-118884D01*
Y-120884D01*
X38293Y-121883D01*
X42292D01*
X43291Y-120884D01*
Y-118884D01*
X42292Y-117885D01*
X40292D01*
Y-119884D01*
X43291Y-115885D02*
X37293D01*
X43291Y-111887D01*
X37293D01*
X38293Y-105889D02*
X37293Y-106888D01*
Y-108888D01*
X38293Y-109887D01*
X39293D01*
X40292Y-108888D01*
Y-106888D01*
X41292Y-105889D01*
X42292D01*
X43291Y-106888D01*
Y-108888D01*
X42292Y-109887D01*
X38293Y-99891D02*
X37293Y-100890D01*
Y-102890D01*
X38293Y-103889D01*
X39293D01*
X40292Y-102890D01*
Y-100890D01*
X41292Y-99891D01*
X42292D01*
X43291Y-100890D01*
Y-102890D01*
X42292Y-103889D01*
X43291Y-93893D02*
Y-97891D01*
X39293Y-93893D01*
X38293D01*
X37293Y-94892D01*
Y-96891D01*
X38293Y-97891D01*
X134012Y-124429D02*
X128014D01*
Y-121430D01*
X129014Y-120430D01*
X131013D01*
X132013Y-121430D01*
Y-124429D01*
X134012Y-118431D02*
Y-116431D01*
Y-117431D01*
X128014D01*
X129014Y-118431D01*
X654454Y-267867D02*
Y-273865D01*
X651455D01*
X650455Y-272866D01*
Y-270866D01*
X651455Y-269866D01*
X654454D01*
X652455D02*
X650455Y-267867D01*
X645457D02*
Y-273865D01*
X648456Y-270866D01*
X644457D01*
X639459Y-267867D02*
Y-273865D01*
X642458Y-270866D01*
X638459D01*
X693550Y-270061D02*
X687552D01*
Y-273060D01*
X688552Y-274060D01*
X692551D01*
X693550Y-273060D01*
Y-270061D01*
X687552Y-276060D02*
Y-278059D01*
Y-277059D01*
X693550D01*
X692551Y-276060D01*
X688552Y-281058D02*
X687552Y-282058D01*
Y-284057D01*
X688552Y-285057D01*
X692551D01*
X693550Y-284057D01*
Y-282058D01*
X692551Y-281058D01*
X691551D01*
X690551Y-282058D01*
Y-285057D01*
X693944Y-220455D02*
X687946D01*
Y-223454D01*
X688945Y-224454D01*
X692944D01*
X693944Y-223454D01*
Y-220455D01*
X687946Y-226453D02*
Y-228453D01*
Y-227453D01*
X693944D01*
X692944Y-226453D01*
X687946Y-235450D02*
Y-231452D01*
X691945Y-235450D01*
X692944D01*
X693944Y-234451D01*
Y-232451D01*
X692944Y-231452D01*
X374827Y-315049D02*
Y-317048D01*
Y-316048D01*
X379825D01*
X380825Y-317048D01*
Y-318048D01*
X379825Y-319047D01*
X375826Y-313049D02*
X374827Y-312050D01*
Y-310050D01*
X375826Y-309051D01*
X376826D01*
X377826Y-310050D01*
Y-311050D01*
Y-310050D01*
X378825Y-309051D01*
X379825D01*
X380825Y-310050D01*
Y-312050D01*
X379825Y-313049D01*
X374827Y-307051D02*
Y-303053D01*
X375826D01*
X379825Y-307051D01*
X380825D01*
X334453Y-177962D02*
X332454D01*
X333453D01*
Y-182960D01*
X332454Y-183960D01*
X331454D01*
X330454Y-182960D01*
X336452Y-178962D02*
X337452Y-177962D01*
X339451D01*
X340451Y-178962D01*
Y-179961D01*
X339451Y-180961D01*
X338452D01*
X339451D01*
X340451Y-181961D01*
Y-182960D01*
X339451Y-183960D01*
X337452D01*
X336452Y-182960D01*
X346449Y-177962D02*
X344450Y-178962D01*
X342450Y-180961D01*
Y-182960D01*
X343450Y-183960D01*
X345449D01*
X346449Y-182960D01*
Y-181961D01*
X345449Y-180961D01*
X342450D01*
X486993Y-154025D02*
Y-152026D01*
Y-153026D01*
X481994D01*
X480995Y-152026D01*
Y-151026D01*
X481994Y-150027D01*
X485993Y-156025D02*
X486993Y-157024D01*
Y-159024D01*
X485993Y-160023D01*
X484993D01*
X483994Y-159024D01*
Y-158024D01*
Y-159024D01*
X482994Y-160023D01*
X481994D01*
X480995Y-159024D01*
Y-157024D01*
X481994Y-156025D01*
X486993Y-166021D02*
Y-162023D01*
X483994D01*
X484993Y-164022D01*
Y-165022D01*
X483994Y-166021D01*
X481994D01*
X480995Y-165022D01*
Y-163022D01*
X481994Y-162023D01*
X534847Y-290128D02*
X536846D01*
X535846D01*
Y-285129D01*
X536846Y-284130D01*
X537846D01*
X538845Y-285129D01*
X532847Y-289128D02*
X531848Y-290128D01*
X529848D01*
X528849Y-289128D01*
Y-288128D01*
X529848Y-287129D01*
X530848D01*
X529848D01*
X528849Y-286129D01*
Y-285129D01*
X529848Y-284130D01*
X531848D01*
X532847Y-285129D01*
X523850Y-284130D02*
Y-290128D01*
X526849Y-287129D01*
X522851D01*
X305036Y-265843D02*
X307036D01*
X306036D01*
Y-260845D01*
X307036Y-259845D01*
X308035D01*
X309035Y-260845D01*
X303037Y-264843D02*
X302037Y-265843D01*
X300038D01*
X299038Y-264843D01*
Y-263844D01*
X300038Y-262844D01*
X301038D01*
X300038D01*
X299038Y-261844D01*
Y-260845D01*
X300038Y-259845D01*
X302037D01*
X303037Y-260845D01*
X297039Y-259845D02*
X295040D01*
X296039D01*
Y-265843D01*
X297039Y-264843D01*
X628391Y-1332D02*
X626392D01*
X627391D01*
Y-6330D01*
X626392Y-7330D01*
X625392D01*
X624392Y-6330D01*
X630390Y-7330D02*
X632390D01*
X631390D01*
Y-1332D01*
X630390Y-2331D01*
X635389D02*
X636388Y-1332D01*
X638388D01*
X639387Y-2331D01*
Y-3331D01*
X638388Y-4331D01*
X637388D01*
X638388D01*
X639387Y-5330D01*
Y-6330D01*
X638388Y-7330D01*
X636388D01*
X635389Y-6330D01*
X95457Y-37946D02*
X93458D01*
X94457D01*
Y-42944D01*
X93458Y-43944D01*
X92458D01*
X91458Y-42944D01*
X101455Y-37946D02*
X99456Y-38945D01*
X97456Y-40945D01*
Y-42944D01*
X98456Y-43944D01*
X100455D01*
X101455Y-42944D01*
Y-41945D01*
X100455Y-40945D01*
X97456D01*
D11*
X673228Y-246063D02*
G03*
X673228Y-246063I-492J0D01*
G01*
X673425Y-258268D02*
G03*
X673425Y-258268I-492J0D01*
G01*
X649307Y-8462D02*
G03*
X649307Y-8462I-492J0D01*
G01*
X75103Y-79234D02*
G03*
X75103Y-79234I-492J0D01*
G01*
X515690Y-326029D02*
G03*
X515690Y-326029I-492J0D01*
G01*
X515592Y-342171D02*
G03*
X515592Y-342171I-492J0D01*
G01*
X643209Y-320374D02*
G03*
X643209Y-320374I-492J0D01*
G01*
X661909Y-320473D02*
G03*
X661909Y-320473I-492J0D01*
G01*
X40846Y4921D02*
G03*
X40846Y4921I-492J0D01*
G01*
X33957D02*
G03*
X33957Y4921I-492J0D01*
G01*
X27067D02*
G03*
X27067Y4921I-492J0D01*
G01*
X47736D02*
G03*
X47736Y4921I-492J0D01*
G01*
X90847Y-116142D02*
G03*
X90847Y-116142I-492J0D01*
G01*
X38287Y-255795D02*
G03*
X38287Y-255795I-492J0D01*
G01*
Y-150480D02*
G03*
X38287Y-150480I-492J0D01*
G01*
Y-309929D02*
G03*
X38287Y-309929I-492J0D01*
G01*
Y-203630D02*
G03*
X38287Y-203630I-492J0D01*
G01*
X280020Y-110600D02*
G03*
X280020Y-110600I-492J0D01*
G01*
X209744Y-111053D02*
G03*
X209744Y-111053I-492J0D01*
G01*
X476968Y-121899D02*
G03*
X476968Y-121899I-492J0D01*
G01*
X523524Y-121013D02*
G03*
X523524Y-121013I-492J0D01*
G01*
X464862Y-117134D02*
G03*
X464862Y-117134I-492J0D01*
G01*
D12*
X393217Y-174277D02*
G03*
X393217Y-174277I-788J0D01*
G01*
X515383Y-195564D02*
G03*
X515383Y-195564I-788J0D01*
G01*
X470179Y-294797D02*
G03*
X470179Y-294797I-788J0D01*
G01*
X355492Y-272526D02*
G03*
X355492Y-272526I-788J0D01*
G01*
D13*
X561791Y-352539D02*
G03*
X561791Y-352539I-2500J0D01*
G01*
X31216Y-189189D02*
G03*
X31216Y-189189I-1000J0D01*
G01*
Y-296866D02*
G03*
X31216Y-296866I-1000J0D01*
G01*
X177362Y-125079D02*
Y-115079D01*
X137362Y-125079D02*
X177362D01*
X137362Y-115079D02*
X177362D01*
X137362Y-125079D02*
Y-115079D01*
X340354Y-121457D02*
X343110D01*
X340354Y-128150D02*
X343110D01*
X364370Y-132874D02*
X367126D01*
X364370Y-139567D02*
X367126D01*
X660532Y-241634D02*
X664862D01*
X680807D02*
X685138D01*
Y-213484D01*
X660532D02*
X664862D01*
X680807D02*
X685138D01*
X660532Y-241634D02*
Y-213484D01*
X646654Y-263583D02*
X649409D01*
X646654Y-256890D02*
X649409D01*
X680807Y-262697D02*
X685138D01*
X660532D02*
X664862D01*
X660532Y-290846D02*
Y-262697D01*
X680807Y-290846D02*
X685138D01*
X660532D02*
X664862D01*
X685138D02*
Y-262697D01*
X363583Y-121457D02*
X366339D01*
X363583Y-128150D02*
X366339D01*
X647689Y-10250D02*
Y-9832D01*
X631941Y-10250D02*
Y-9832D01*
X647689D01*
X631941Y-41840D02*
X647689D01*
Y-41423D01*
X631941Y-41840D02*
Y-41423D01*
X549291Y-348287D02*
X565413D01*
X613169D02*
X629291D01*
X613169Y-311791D02*
X629291D01*
X549291D02*
X565413D01*
X629291Y-348287D02*
Y-311791D01*
X549291Y-348287D02*
Y-311791D01*
X91484Y-46273D02*
Y-45856D01*
X75736Y-46273D02*
Y-45856D01*
X91484D01*
X75736Y-77864D02*
X91484D01*
Y-77447D01*
X75736Y-77864D02*
Y-77447D01*
X-13898Y-330561D02*
X-3032D01*
X-22244Y-322214D02*
Y-311348D01*
X5315Y-322214D02*
Y-311348D01*
X-13898Y-303002D02*
X-3032D01*
X-13898Y-277410D02*
X-3032D01*
X-22244Y-269063D02*
Y-258197D01*
X5315Y-269063D02*
Y-258197D01*
X-13898Y-249850D02*
X-3032D01*
X-13898Y-224260D02*
X-3032D01*
X-22244Y-215913D02*
Y-205047D01*
X5315Y-215913D02*
Y-205047D01*
X-13898Y-196701D02*
X-3032D01*
X-13898Y-171112D02*
X-3032D01*
X-22244Y-162765D02*
Y-151899D01*
X5315Y-162765D02*
Y-151899D01*
X-13898Y-143553D02*
X-3032D01*
X518348Y-327407D02*
X522285D01*
Y-329179D02*
Y-327407D01*
X518348Y-336069D02*
X522285D01*
Y-334297D01*
X518249Y-343549D02*
X522186D01*
Y-345321D02*
Y-343549D01*
X518249Y-352210D02*
X522186D01*
Y-350439D01*
X641339Y-327461D02*
Y-323524D01*
X639567Y-327461D02*
X641339D01*
X632677D02*
Y-323524D01*
Y-327461D02*
X634449D01*
X660039Y-327559D02*
Y-323622D01*
X658268Y-327559D02*
X660039D01*
X651378D02*
Y-323622D01*
Y-327559D02*
X653150D01*
X72638Y-216535D02*
X78937D01*
X72638D02*
Y-208661D01*
X78937D01*
Y-216535D02*
Y-208661D01*
X80315Y-217520D02*
X83661D01*
X71653Y-163386D02*
X77953D01*
X71653D02*
Y-155512D01*
X77953D01*
Y-163386D02*
Y-155512D01*
X79331Y-164370D02*
X82677D01*
X37205Y8465D02*
Y15157D01*
X43504Y8465D02*
Y15157D01*
X30315Y8465D02*
Y15157D01*
X36614Y8465D02*
Y15157D01*
X23425Y8465D02*
Y15157D01*
X29724Y8465D02*
Y15157D01*
X44094Y8465D02*
Y15157D01*
X50394Y8465D02*
Y15157D01*
X92913Y-117913D02*
Y-115551D01*
X95276D01*
X111417D02*
X113779D01*
Y-117913D02*
Y-115551D01*
Y-136417D02*
Y-134055D01*
X111417Y-136417D02*
X113779D01*
X92913D02*
Y-134055D01*
Y-136417D02*
X95276D01*
X80905Y-113287D02*
Y-113091D01*
X84449Y-113287D02*
Y-113091D01*
X72539Y-128839D02*
Y-121949D01*
X79035Y-128839D02*
Y-121949D01*
X72638Y-268701D02*
X78937D01*
X72638D02*
Y-260827D01*
X78937D01*
Y-268701D02*
Y-260827D01*
X80315Y-269685D02*
X83661D01*
X49409Y-264961D02*
Y-260630D01*
Y-159646D02*
Y-155315D01*
X71653Y-322835D02*
X77953D01*
X71653D02*
Y-314961D01*
X77953D01*
Y-322835D02*
Y-314961D01*
X79331Y-323819D02*
X82677D01*
X49409Y-319094D02*
Y-314764D01*
Y-212795D02*
Y-208465D01*
X534055Y-1063D02*
X594055D01*
Y18937D01*
X534055D02*
X594055D01*
X534055Y-1063D02*
Y18937D01*
X647146Y-56053D02*
X648130D01*
X647146Y-61761D02*
X648130D01*
X612697Y-18651D02*
X613681D01*
X612697Y-24360D02*
X613681D01*
X86713Y-94832D02*
Y-93848D01*
X92421Y-94832D02*
Y-93848D01*
X120177Y-76525D02*
Y-75541D01*
X125886Y-76525D02*
Y-75541D01*
X27756Y-171653D02*
X41142D01*
Y-187795D02*
Y-171653D01*
X27756Y-187795D02*
Y-171653D01*
Y-187795D02*
X41043D01*
X27756Y-279331D02*
X41142D01*
Y-295472D02*
Y-279331D01*
X27756Y-295472D02*
Y-279331D01*
Y-295472D02*
X41043D01*
X285433Y-131289D02*
Y-111604D01*
X292520Y-131289D02*
Y-111604D01*
X285433D02*
X292520D01*
X285433Y-131289D02*
X292520D01*
X214567Y-131742D02*
Y-112057D01*
X222441Y-131742D02*
Y-112057D01*
X214567D02*
X222441D01*
X214567Y-131742D02*
X222441D01*
X477953Y-117569D02*
X494488D01*
Y-132135D02*
Y-117569D01*
X477953Y-132135D02*
X494488D01*
X477953D02*
Y-117569D01*
X510630Y-118750D02*
X520866D01*
X510630Y-130954D02*
X520866D01*
X454921Y-126514D02*
Y-125159D01*
X459414Y-128986D02*
X461846D01*
X466339Y-126514D02*
Y-125159D01*
D14*
X-18799Y-190157D02*
G03*
X-18406Y-190157I197J0D01*
G01*
D02*
G03*
X-18799Y-190157I-197J0D01*
G01*
Y-242913D02*
G03*
X-18406Y-242913I197J0D01*
G01*
D02*
G03*
X-18799Y-242913I-197J0D01*
G01*
Y-296457D02*
G03*
X-18406Y-296457I197J0D01*
G01*
D02*
G03*
X-18799Y-296457I-197J0D01*
G01*
Y-349213D02*
G03*
X-18406Y-349213I197J0D01*
G01*
D02*
G03*
X-18799Y-349213I-197J0D01*
G01*
Y-116339D02*
G03*
X-18406Y-116339I197J0D01*
G01*
D02*
G03*
X-18799Y-116339I-197J0D01*
G01*
Y-73032D02*
G03*
X-18406Y-73032I197J0D01*
G01*
D02*
G03*
X-18799Y-73032I-197J0D01*
G01*
X626083Y-127264D02*
G03*
X626083Y-127264I-197J0D01*
G01*
X-16437Y-185433D02*
Y-179134D01*
Y-238189D02*
Y-231890D01*
Y-291732D02*
Y-285433D01*
Y-344488D02*
Y-338189D01*
Y-111614D02*
Y-105315D01*
Y-68307D02*
Y-62008D01*
D15*
X289370Y-114753D02*
G03*
X289370Y-114753I-787J0D01*
G01*
X218504Y-115206D02*
G03*
X218504Y-115206I-787J0D01*
G01*
D16*
X558576Y-246791D02*
Y-225532D01*
X578261Y-241280D02*
Y-225532D01*
X569156Y-138279D02*
Y-122531D01*
X549471Y-143791D02*
Y-122531D01*
D17*
X552419Y-233874D02*
Y-229937D01*
X547919Y-244706D02*
X553919D01*
X547919Y-237105D02*
X553919D01*
X614719Y-243406D02*
Y-237405D01*
X607119Y-243406D02*
Y-237405D01*
X625719Y-243406D02*
Y-237405D01*
X618119Y-243406D02*
Y-237405D01*
X580167Y-230512D02*
X584104D01*
X580450Y-219905D02*
X584387D01*
X573474Y-208858D02*
Y-204921D01*
X562919Y-252105D02*
X567919D01*
X562919Y-257705D02*
X567919D01*
X536556Y-334738D02*
Y-328738D01*
X536162Y-350880D02*
Y-344880D01*
X652118Y-342520D02*
X658118D01*
X634008Y-342913D02*
X640008D01*
X644625Y-240795D02*
Y-234795D01*
X652225Y-240795D02*
Y-234795D01*
X573813Y-119174D02*
Y-115237D01*
X651575Y-251575D02*
Y-247638D01*
X353680Y-103394D02*
Y-97394D01*
X361280Y-103394D02*
Y-97394D01*
X551225Y-156437D02*
Y-151437D01*
X545625Y-156437D02*
Y-151437D01*
X539313Y-134606D02*
X545313D01*
X539313Y-142206D02*
X545313D01*
X619983Y-136280D02*
X625983D01*
X619983Y-128680D02*
X625983D01*
X619983Y-144942D02*
X625983D01*
X619983Y-137342D02*
X625983D01*
X621014Y-120276D02*
Y-116339D01*
X543313Y-130374D02*
Y-126437D01*
X571802Y-138779D02*
X575739D01*
X563928Y-107283D02*
Y-103347D01*
X113425Y-265600D02*
Y-261663D01*
D18*
X618016Y-148917D02*
X700758D01*
X618016Y-204823D02*
Y-148917D01*
X622274Y-204823D02*
X700758D01*
X599055Y939D02*
X595723D01*
Y1772D01*
X599055Y5104D01*
Y5937D01*
Y15937D02*
X597389D01*
X598222D01*
Y10939D01*
X599055Y11772D01*
X527723Y10939D02*
X529389Y11772D01*
X531055Y13438D01*
Y15104D01*
X530222Y15937D01*
X528556D01*
X527723Y15104D01*
Y14271D01*
X528556Y13438D01*
X531055D01*
Y5937D02*
X529389D01*
X530222D01*
Y939D01*
X531055Y1772D01*
X523558Y5937D02*
X526890D01*
X523558Y2605D01*
Y1772D01*
X524391Y939D01*
X526057D01*
X526890Y1772D01*
D19*
X618053Y-204823D02*
X622274D01*
D20*
X470414Y-168351D02*
X473040D01*
Y-165989D01*
X475206D01*
Y-154965D01*
X473040D02*
X475206D01*
X473040D02*
Y-152603D01*
X470414D02*
X473040D01*
X388789Y-168351D02*
X391415D01*
X388789D02*
Y-165989D01*
X386624D02*
X388789D01*
X386624D02*
Y-154965D01*
X388789D01*
Y-152603D01*
X391415D01*
X520521Y-276176D02*
Y-273550D01*
Y-276176D02*
X522883D01*
Y-278341D02*
Y-276176D01*
Y-278341D02*
X533907D01*
Y-276176D01*
X536269D01*
Y-273550D01*
X520521Y-194550D02*
Y-191924D01*
X522883D01*
Y-189759D01*
X533907D01*
Y-191924D02*
Y-189759D01*
Y-191924D02*
X536269D01*
Y-194550D02*
Y-191924D01*
X388779Y-300724D02*
X391405D01*
X388779Y-303085D02*
Y-300724D01*
X386614Y-303085D02*
X388779D01*
X386614Y-314109D02*
Y-303085D01*
Y-314109D02*
X388779D01*
Y-316472D02*
Y-314109D01*
Y-316472D02*
X391405D01*
X470405Y-300724D02*
X473031D01*
Y-303085D02*
Y-300724D01*
Y-303085D02*
X475196D01*
Y-314109D02*
Y-303085D01*
X473031Y-314109D02*
X475196D01*
X473031Y-316472D02*
Y-314109D01*
X470405Y-316472D02*
X473031D01*
X348778Y-194540D02*
Y-191914D01*
X346416D02*
X348778D01*
X346416D02*
Y-189749D01*
X335392D02*
X346416D01*
X335392Y-191914D02*
Y-189749D01*
X333030Y-191914D02*
X335392D01*
X333030Y-194540D02*
Y-191914D01*
X348778Y-276166D02*
Y-273540D01*
X346416Y-276166D02*
X348778D01*
X346416Y-278331D02*
Y-276166D01*
X335392Y-278331D02*
X346416D01*
X335392D02*
Y-276166D01*
X333030D02*
X335392D01*
X333030D02*
Y-273540D01*
D21*
X326304Y-145674D02*
X542840D01*
X326304Y-322840D02*
X542840D01*
Y-145674D01*
X326304Y-322840D02*
Y-145674D01*
D22*
X320979Y-112880D02*
X321978D01*
X321479D01*
Y-109880D01*
X320979Y-110380D01*
X325477Y-112880D02*
X323478D01*
X325477Y-110880D01*
Y-110380D01*
X324977Y-109880D01*
X323978D01*
X323478Y-110380D01*
X326477Y-109880D02*
Y-111880D01*
X327477Y-112880D01*
X328476Y-111880D01*
Y-109880D01*
X332475Y-112880D02*
Y-109880D01*
X333475Y-110880D01*
X334474Y-109880D01*
Y-112880D01*
X335474D02*
Y-110880D01*
X336474Y-109880D01*
X337473Y-110880D01*
Y-112880D01*
Y-111380D01*
X335474D01*
X340472Y-110380D02*
X339973Y-109880D01*
X338973D01*
X338473Y-110380D01*
Y-112380D01*
X338973Y-112880D01*
X339973D01*
X340472Y-112380D01*
X378459Y-139908D02*
X378959Y-139408D01*
X379959D01*
X380458Y-139908D01*
Y-140408D01*
X379959Y-140908D01*
X379459D01*
X379959D01*
X380458Y-141407D01*
Y-141907D01*
X379959Y-142407D01*
X378959D01*
X378459Y-141907D01*
X381458Y-142407D02*
Y-141907D01*
X381958D01*
Y-142407D01*
X381458D01*
X383957Y-139908D02*
X384457Y-139408D01*
X385457D01*
X385957Y-139908D01*
Y-140408D01*
X385457Y-140908D01*
X384957D01*
X385457D01*
X385957Y-141407D01*
Y-141907D01*
X385457Y-142407D01*
X384457D01*
X383957Y-141907D01*
X386956Y-139408D02*
Y-141407D01*
X387956Y-142407D01*
X388956Y-141407D01*
Y-139408D01*
X392954Y-142407D02*
Y-139408D01*
X393954Y-140408D01*
X394954Y-139408D01*
Y-142407D01*
X395953D02*
Y-140408D01*
X396953Y-139408D01*
X397953Y-140408D01*
Y-142407D01*
Y-140908D01*
X395953D01*
X400952Y-139908D02*
X400452Y-139408D01*
X399452D01*
X398952Y-139908D01*
Y-141907D01*
X399452Y-142407D01*
X400452D01*
X400952Y-141907D01*
X371797Y-108306D02*
X369798D01*
Y-109805D01*
X370797Y-109305D01*
X371297D01*
X371797Y-109805D01*
Y-110805D01*
X371297Y-111305D01*
X370298D01*
X369798Y-110805D01*
X372797Y-108306D02*
Y-110305D01*
X373796Y-111305D01*
X374796Y-110305D01*
Y-108306D01*
X378795Y-111305D02*
Y-108306D01*
X379794Y-109305D01*
X380794Y-108306D01*
Y-111305D01*
X381794D02*
Y-109305D01*
X382793Y-108306D01*
X383793Y-109305D01*
Y-111305D01*
Y-109805D01*
X381794D01*
X386792Y-108806D02*
X386292Y-108306D01*
X385293D01*
X384793Y-108806D01*
Y-110805D01*
X385293Y-111305D01*
X386292D01*
X386792Y-110805D01*
X161167Y-128491D02*
X160667Y-127991D01*
X159668D01*
X159168Y-128491D01*
Y-130490D01*
X159668Y-130990D01*
X160667D01*
X161167Y-130490D01*
Y-129490D01*
X160167D01*
X162167Y-130990D02*
Y-127991D01*
X164166Y-130990D01*
Y-127991D01*
X165166D02*
Y-130990D01*
X166665D01*
X167165Y-130490D01*
Y-128491D01*
X166665Y-127991D01*
X165166D01*
X170979Y-127597D02*
Y-129596D01*
X171978Y-130596D01*
X172978Y-129596D01*
Y-127597D01*
X175977Y-128097D02*
X175477Y-127597D01*
X174478D01*
X173978Y-128097D01*
Y-130096D01*
X174478Y-130596D01*
X175477D01*
X175977Y-130096D01*
X178976Y-128097D02*
X178476Y-127597D01*
X177477D01*
X176977Y-128097D01*
Y-130096D01*
X177477Y-130596D01*
X178476D01*
X178976Y-130096D01*
X149356Y-128491D02*
X148856Y-127991D01*
X147856D01*
X147357Y-128491D01*
Y-128990D01*
X147856Y-129490D01*
X148856D01*
X149356Y-129990D01*
Y-130490D01*
X148856Y-130990D01*
X147856D01*
X147357Y-130490D01*
X152355Y-128491D02*
X151855Y-127991D01*
X150856D01*
X150356Y-128491D01*
Y-130490D01*
X150856Y-130990D01*
X151855D01*
X152355Y-130490D01*
X153355Y-127991D02*
Y-130990D01*
X155354D01*
X137939Y-128491D02*
X137439Y-127991D01*
X136439D01*
X135939Y-128491D01*
Y-128990D01*
X136439Y-129490D01*
X137439D01*
X137939Y-129990D01*
Y-130490D01*
X137439Y-130990D01*
X136439D01*
X135939Y-130490D01*
X138938Y-127991D02*
Y-130990D01*
X140438D01*
X140938Y-130490D01*
Y-128491D01*
X140438Y-127991D01*
X138938D01*
X141937Y-130990D02*
Y-128990D01*
X142937Y-127991D01*
X143937Y-128990D01*
Y-130990D01*
Y-129490D01*
X141937D01*
X379072Y-136145D02*
Y-133146D01*
X380572D01*
X381071Y-133646D01*
Y-134646D01*
X380572Y-135145D01*
X379072D01*
X380072D02*
X381071Y-136145D01*
X383571D02*
Y-133146D01*
X382071Y-134646D01*
X384071D01*
X385070Y-133146D02*
X387070D01*
Y-133646D01*
X385070Y-135645D01*
Y-136145D01*
X612749Y-203513D02*
Y-204512D01*
Y-204012D01*
X615248D01*
X615748Y-204512D01*
Y-205012D01*
X615248Y-205512D01*
X613249Y-202513D02*
X612749Y-202013D01*
Y-201013D01*
X613249Y-200513D01*
X613749D01*
X614249Y-201013D01*
Y-201513D01*
Y-201013D01*
X614748Y-200513D01*
X615248D01*
X615748Y-201013D01*
Y-202013D01*
X615248Y-202513D01*
X613249Y-199514D02*
X612749Y-199014D01*
Y-198014D01*
X613249Y-197514D01*
X613749D01*
X614249Y-198014D01*
X614748Y-197514D01*
X615248D01*
X615748Y-198014D01*
Y-199014D01*
X615248Y-199514D01*
X614748D01*
X614249Y-199014D01*
X613749Y-199514D01*
X613249D01*
X614249Y-199014D02*
Y-198014D01*
X330647Y-117641D02*
Y-114642D01*
X332147D01*
X332646Y-115142D01*
Y-116142D01*
X332147Y-116642D01*
X330647D01*
X331647D02*
X332646Y-117641D01*
X335145D02*
Y-114642D01*
X333646Y-116142D01*
X335645D01*
X338644Y-114642D02*
X337645Y-115142D01*
X336645Y-116142D01*
Y-117141D01*
X337145Y-117641D01*
X338144D01*
X338644Y-117141D01*
Y-116642D01*
X338144Y-116142D01*
X336645D01*
X370804Y-117247D02*
Y-114249D01*
X372304D01*
X372804Y-114748D01*
Y-115748D01*
X372304Y-116248D01*
X370804D01*
X371804D02*
X372804Y-117247D01*
X375303D02*
Y-114249D01*
X373803Y-115748D01*
X375803D01*
X378802Y-114249D02*
X376802D01*
Y-115748D01*
X377802Y-115248D01*
X378302D01*
X378802Y-115748D01*
Y-116748D01*
X378302Y-117247D01*
X377302D01*
X376802Y-116748D01*
X242458Y-133783D02*
Y-130784D01*
X243957D01*
X244457Y-131284D01*
Y-132283D01*
X243957Y-132783D01*
X242458D01*
X243458D02*
X244457Y-133783D01*
X246956D02*
Y-130784D01*
X245457Y-132283D01*
X247456D01*
X248456Y-131284D02*
X248956Y-130784D01*
X249956D01*
X250455Y-131284D01*
Y-131784D01*
X249956Y-132283D01*
X249456D01*
X249956D01*
X250455Y-132783D01*
Y-133283D01*
X249956Y-133783D01*
X248956D01*
X248456Y-133283D01*
X266474Y-134964D02*
Y-131965D01*
X267973D01*
X268473Y-132465D01*
Y-133465D01*
X267973Y-133964D01*
X266474D01*
X267473D02*
X268473Y-134964D01*
X270972D02*
Y-131965D01*
X269473Y-133465D01*
X271472D01*
X274471Y-134964D02*
X272472D01*
X274471Y-132965D01*
Y-132465D01*
X273971Y-131965D01*
X272972D01*
X272472Y-132465D01*
X38855Y-18513D02*
X41854D01*
Y-17013D01*
X41354Y-16513D01*
X39355D01*
X38855Y-17013D01*
Y-18513D01*
X41854Y-15514D02*
Y-14514D01*
Y-15014D01*
X38855D01*
X39355Y-15514D01*
Y-13014D02*
X38855Y-12515D01*
Y-11515D01*
X39355Y-11015D01*
X41354D01*
X41854Y-11515D01*
Y-12515D01*
X41354Y-13014D01*
X39355D01*
X30981Y-18247D02*
X33980D01*
Y-16748D01*
X33480Y-16248D01*
X31481D01*
X30981Y-16748D01*
Y-18247D01*
X33480Y-15248D02*
X33980Y-14748D01*
Y-13749D01*
X33480Y-13249D01*
X31481D01*
X30981Y-13749D01*
Y-14748D01*
X31481Y-15248D01*
X31980D01*
X32480Y-14748D01*
Y-13249D01*
X25075Y-18247D02*
X28074D01*
Y-16748D01*
X27575Y-16248D01*
X25575D01*
X25075Y-16748D01*
Y-18247D01*
X25575Y-15248D02*
X25075Y-14748D01*
Y-13749D01*
X25575Y-13249D01*
X26075D01*
X26575Y-13749D01*
Y-14248D01*
Y-13749D01*
X27075Y-13249D01*
X27575D01*
X28074Y-13749D01*
Y-14748D01*
X27575Y-15248D01*
X78552Y-312523D02*
Y-310024D01*
X78052Y-309524D01*
X77052D01*
X76553Y-310024D01*
Y-312523D01*
X75553Y-309524D02*
X74553D01*
X75053D01*
Y-312523D01*
X75553Y-312023D01*
X71054Y-312523D02*
X72054Y-312023D01*
X73054Y-311024D01*
Y-310024D01*
X72554Y-309524D01*
X71554D01*
X71054Y-310024D01*
Y-310524D01*
X71554Y-311024D01*
X73054D01*
X79536Y-206224D02*
Y-203725D01*
X79036Y-203225D01*
X78037D01*
X77537Y-203725D01*
Y-206224D01*
X76537Y-203225D02*
X75538D01*
X76037D01*
Y-206224D01*
X76537Y-205724D01*
X72039Y-203225D02*
X74038D01*
X72039Y-205224D01*
Y-205724D01*
X72538Y-206224D01*
X73538D01*
X74038Y-205724D01*
X79332Y-258389D02*
Y-255890D01*
X78832Y-255390D01*
X77832D01*
X77332Y-255890D01*
Y-258389D01*
X76333Y-255390D02*
X75333D01*
X75833D01*
Y-258389D01*
X76333Y-257889D01*
X73833Y-255390D02*
X72834D01*
X73334D01*
Y-258389D01*
X73833Y-257889D01*
X77302Y-153074D02*
Y-150575D01*
X76802Y-150075D01*
X75803D01*
X75303Y-150575D01*
Y-153074D01*
X74303Y-152575D02*
X73803Y-153074D01*
X72804D01*
X72304Y-152575D01*
Y-152075D01*
X72804Y-151575D01*
X72304Y-151075D01*
Y-150575D01*
X72804Y-150075D01*
X73803D01*
X74303Y-150575D01*
Y-151075D01*
X73803Y-151575D01*
X74303Y-152075D01*
Y-152575D01*
X73803Y-151575D02*
X72804D01*
X91005Y-109721D02*
Y-112220D01*
X91505Y-112720D01*
X92504D01*
X93004Y-112220D01*
Y-109721D01*
X96003D02*
X95003Y-110221D01*
X94004Y-111221D01*
Y-112220D01*
X94504Y-112720D01*
X95503D01*
X96003Y-112220D01*
Y-111720D01*
X95503Y-111221D01*
X94004D01*
X65399Y-137326D02*
Y-134327D01*
X66898D01*
X67398Y-134827D01*
Y-135827D01*
X66898Y-136327D01*
X65399D01*
X66398D02*
X67398Y-137326D01*
X69897D02*
Y-134327D01*
X68398Y-135827D01*
X70397D01*
X71397Y-137326D02*
X72396D01*
X71897D01*
Y-134327D01*
X71397Y-134827D01*
X70397Y-118172D02*
X67398D01*
Y-116672D01*
X67898Y-116173D01*
X68898D01*
X69397Y-116672D01*
Y-118172D01*
Y-117172D02*
X70397Y-116173D01*
Y-113673D02*
X67398D01*
X68898Y-115173D01*
Y-113174D01*
X67898Y-112174D02*
X67398Y-111674D01*
Y-110674D01*
X67898Y-110175D01*
X69897D01*
X70397Y-110674D01*
Y-111674D01*
X69897Y-112174D01*
X67898D01*
X48744Y-29589D02*
X45745D01*
Y-28090D01*
X46244Y-27590D01*
X47244D01*
X47744Y-28090D01*
Y-29589D01*
Y-28590D02*
X48744Y-27590D01*
X46244Y-26590D02*
X45745Y-26090D01*
Y-25091D01*
X46244Y-24591D01*
X46744D01*
X47244Y-25091D01*
Y-25591D01*
Y-25091D01*
X47744Y-24591D01*
X48244D01*
X48744Y-25091D01*
Y-26090D01*
X48244Y-26590D01*
Y-23591D02*
X48744Y-23091D01*
Y-22092D01*
X48244Y-21592D01*
X46244D01*
X45745Y-22092D01*
Y-23091D01*
X46244Y-23591D01*
X46744D01*
X47244Y-23091D01*
Y-21592D01*
X41854Y-29589D02*
X38855D01*
Y-28090D01*
X39355Y-27590D01*
X40354D01*
X40854Y-28090D01*
Y-29589D01*
Y-28590D02*
X41854Y-27590D01*
X39355Y-26590D02*
X38855Y-26090D01*
Y-25091D01*
X39355Y-24591D01*
X39854D01*
X40354Y-25091D01*
Y-25591D01*
Y-25091D01*
X40854Y-24591D01*
X41354D01*
X41854Y-25091D01*
Y-26090D01*
X41354Y-26590D01*
X39355Y-23591D02*
X38855Y-23091D01*
Y-22092D01*
X39355Y-21592D01*
X39854D01*
X40354Y-22092D01*
X40854Y-21592D01*
X41354D01*
X41854Y-22092D01*
Y-23091D01*
X41354Y-23591D01*
X40854D01*
X40354Y-23091D01*
X39854Y-23591D01*
X39355D01*
X40354Y-23091D02*
Y-22092D01*
X33980Y-29589D02*
X30981D01*
Y-28090D01*
X31481Y-27590D01*
X32480D01*
X32980Y-28090D01*
Y-29589D01*
Y-28590D02*
X33980Y-27590D01*
X31481Y-26590D02*
X30981Y-26090D01*
Y-25091D01*
X31481Y-24591D01*
X31980D01*
X32480Y-25091D01*
Y-25591D01*
Y-25091D01*
X32980Y-24591D01*
X33480D01*
X33980Y-25091D01*
Y-26090D01*
X33480Y-26590D01*
X30981Y-21592D02*
X31481Y-22591D01*
X32480Y-23591D01*
X33480D01*
X33980Y-23091D01*
Y-22092D01*
X33480Y-21592D01*
X32980D01*
X32480Y-22092D01*
Y-23591D01*
X28074Y-29589D02*
X25075D01*
Y-28090D01*
X25575Y-27590D01*
X26575D01*
X27075Y-28090D01*
Y-29589D01*
Y-28590D02*
X28074Y-27590D01*
X25575Y-26590D02*
X25075Y-26090D01*
Y-25091D01*
X25575Y-24591D01*
X26075D01*
X26575Y-25091D01*
Y-25591D01*
Y-25091D01*
X27075Y-24591D01*
X27575D01*
X28074Y-25091D01*
Y-26090D01*
X27575Y-26590D01*
X25075Y-21592D02*
Y-23591D01*
X26575D01*
X26075Y-22591D01*
Y-22092D01*
X26575Y-21592D01*
X27575D01*
X28074Y-22092D01*
Y-23091D01*
X27575Y-23591D01*
X52891Y-312523D02*
Y-309524D01*
X54391D01*
X54890Y-310024D01*
Y-311024D01*
X54391Y-311524D01*
X52891D01*
X53891D02*
X54890Y-312523D01*
X55890Y-310024D02*
X56390Y-309524D01*
X57390D01*
X57889Y-310024D01*
Y-310524D01*
X57390Y-311024D01*
X56890D01*
X57390D01*
X57889Y-311524D01*
Y-312023D01*
X57390Y-312523D01*
X56390D01*
X55890Y-312023D01*
X60389Y-312523D02*
Y-309524D01*
X58889Y-311024D01*
X60888D01*
X54072Y-206224D02*
Y-203225D01*
X55572D01*
X56072Y-203725D01*
Y-204724D01*
X55572Y-205224D01*
X54072D01*
X55072D02*
X56072Y-206224D01*
X57071Y-203725D02*
X57571Y-203225D01*
X58571D01*
X59071Y-203725D01*
Y-204225D01*
X58571Y-204724D01*
X58071D01*
X58571D01*
X59071Y-205224D01*
Y-205724D01*
X58571Y-206224D01*
X57571D01*
X57071Y-205724D01*
X60070Y-203725D02*
X60570Y-203225D01*
X61570D01*
X62070Y-203725D01*
Y-204225D01*
X61570Y-204724D01*
X61070D01*
X61570D01*
X62070Y-205224D01*
Y-205724D01*
X61570Y-206224D01*
X60570D01*
X60070Y-205724D01*
X76303Y-348487D02*
X73304D01*
Y-346987D01*
X73804Y-346487D01*
X74803D01*
X75303Y-346987D01*
Y-348487D01*
Y-347487D02*
X76303Y-346487D01*
X73804Y-345488D02*
X73304Y-344988D01*
Y-343988D01*
X73804Y-343489D01*
X74303D01*
X74803Y-343988D01*
Y-344488D01*
Y-343988D01*
X75303Y-343489D01*
X75803D01*
X76303Y-343988D01*
Y-344988D01*
X75803Y-345488D01*
X76303Y-340490D02*
Y-342489D01*
X74303Y-340490D01*
X73804D01*
X73304Y-340989D01*
Y-341989D01*
X73804Y-342489D01*
X84177Y-347987D02*
X81178D01*
Y-346487D01*
X81678Y-345988D01*
X82677D01*
X83177Y-346487D01*
Y-347987D01*
Y-346987D02*
X84177Y-345988D01*
X81678Y-344988D02*
X81178Y-344488D01*
Y-343489D01*
X81678Y-342989D01*
X82177D01*
X82677Y-343489D01*
Y-343988D01*
Y-343489D01*
X83177Y-342989D01*
X83677D01*
X84177Y-343489D01*
Y-344488D01*
X83677Y-344988D01*
X84177Y-341989D02*
Y-340989D01*
Y-341489D01*
X81178D01*
X81678Y-341989D01*
X518306Y2086D02*
X515307D01*
Y3586D01*
X515806Y4086D01*
X516806D01*
X517306Y3586D01*
Y2086D01*
X515806Y5085D02*
X515307Y5585D01*
Y6585D01*
X515806Y7085D01*
X516306D01*
X516806Y6585D01*
Y6085D01*
Y6585D01*
X517306Y7085D01*
X517806D01*
X518306Y6585D01*
Y5585D01*
X517806Y5085D01*
X38870Y-304603D02*
X37871D01*
X38370D01*
Y-307102D01*
X37871Y-307602D01*
X37371D01*
X36871Y-307102D01*
X41369Y-307602D02*
Y-304603D01*
X39870Y-306102D01*
X41869D01*
X37886Y-197319D02*
X36886D01*
X37386D01*
Y-199819D01*
X36886Y-200318D01*
X36386D01*
X35887Y-199819D01*
X40885Y-200318D02*
X38886D01*
X40885Y-198319D01*
Y-197819D01*
X40385Y-197319D01*
X39386D01*
X38886Y-197819D01*
X37886Y-249485D02*
X36886D01*
X37386D01*
Y-251984D01*
X36886Y-252484D01*
X36386D01*
X35887Y-251984D01*
X38886Y-249985D02*
X39386Y-249485D01*
X40385D01*
X40885Y-249985D01*
Y-250484D01*
X40385Y-250984D01*
X39885D01*
X40385D01*
X40885Y-251484D01*
Y-251984D01*
X40385Y-252484D01*
X39386D01*
X38886Y-251984D01*
X38386Y-145154D02*
X37386D01*
X37886D01*
Y-147653D01*
X37386Y-148153D01*
X36886D01*
X36386Y-147653D01*
X39386Y-148153D02*
X40385D01*
X39885D01*
Y-145154D01*
X39386Y-145654D01*
X-13310Y-348237D02*
X-10311D01*
Y-346737D01*
X-10811Y-346238D01*
X-12811D01*
X-13310Y-346737D01*
Y-348237D01*
X-10311Y-345238D02*
Y-344238D01*
Y-344738D01*
X-13310D01*
X-12811Y-345238D01*
Y-342739D02*
X-13310Y-342239D01*
Y-341239D01*
X-12811Y-340739D01*
X-12311D01*
X-11811Y-341239D01*
X-11311Y-340739D01*
X-10811D01*
X-10311Y-341239D01*
Y-342239D01*
X-10811Y-342739D01*
X-11311D01*
X-11811Y-342239D01*
X-12311Y-342739D01*
X-12811D01*
X-11811Y-342239D02*
Y-341239D01*
X-13310Y-295087D02*
X-10311D01*
Y-293588D01*
X-10811Y-293088D01*
X-12811D01*
X-13310Y-293588D01*
Y-295087D01*
X-10311Y-292088D02*
Y-291089D01*
Y-291588D01*
X-13310D01*
X-12811Y-292088D01*
X-13310Y-289589D02*
Y-287590D01*
X-12811D01*
X-10811Y-289589D01*
X-10311D01*
X-13310Y-241938D02*
X-10311D01*
Y-240438D01*
X-10811Y-239938D01*
X-12811D01*
X-13310Y-240438D01*
Y-241938D01*
X-10311Y-238939D02*
Y-237939D01*
Y-238439D01*
X-13310D01*
X-12811Y-238939D01*
X-13310Y-234440D02*
X-12811Y-235440D01*
X-11811Y-236439D01*
X-10811D01*
X-10311Y-235940D01*
Y-234940D01*
X-10811Y-234440D01*
X-11311D01*
X-11811Y-234940D01*
Y-236439D01*
X-13310Y-188788D02*
X-10311D01*
Y-187289D01*
X-10811Y-186789D01*
X-12811D01*
X-13310Y-187289D01*
Y-188788D01*
X-10311Y-185789D02*
Y-184789D01*
Y-185289D01*
X-13310D01*
X-12811Y-185789D01*
X-13310Y-181291D02*
Y-183290D01*
X-11811D01*
X-12311Y-182290D01*
Y-181790D01*
X-11811Y-181291D01*
X-10811D01*
X-10311Y-181790D01*
Y-182790D01*
X-10811Y-183290D01*
X67898Y-126999D02*
X67398Y-127499D01*
Y-128499D01*
X67898Y-128999D01*
X69897D01*
X70397Y-128499D01*
Y-127499D01*
X69897Y-126999D01*
X70397Y-124500D02*
X67398D01*
X68898Y-126000D01*
Y-124000D01*
X67898Y-123001D02*
X67398Y-122501D01*
Y-121501D01*
X67898Y-121001D01*
X69897D01*
X70397Y-121501D01*
Y-122501D01*
X69897Y-123001D01*
X67898D01*
X62977Y-116173D02*
X62477Y-116672D01*
Y-117672D01*
X62977Y-118172D01*
X64976D01*
X65476Y-117672D01*
Y-116672D01*
X64976Y-116173D01*
X62977Y-115173D02*
X62477Y-114673D01*
Y-113673D01*
X62977Y-113174D01*
X63477D01*
X63976Y-113673D01*
Y-114173D01*
Y-113673D01*
X64476Y-113174D01*
X64976D01*
X65476Y-113673D01*
Y-114673D01*
X64976Y-115173D01*
Y-112174D02*
X65476Y-111674D01*
Y-110674D01*
X64976Y-110175D01*
X62977D01*
X62477Y-110674D01*
Y-111674D01*
X62977Y-112174D01*
X63477D01*
X63976Y-111674D01*
Y-110175D01*
X62977Y-126999D02*
X62477Y-127499D01*
Y-128499D01*
X62977Y-128999D01*
X64976D01*
X65476Y-128499D01*
Y-127499D01*
X64976Y-126999D01*
X62977Y-126000D02*
X62477Y-125500D01*
Y-124500D01*
X62977Y-124000D01*
X63477D01*
X63976Y-124500D01*
Y-125000D01*
Y-124500D01*
X64476Y-124000D01*
X64976D01*
X65476Y-124500D01*
Y-125500D01*
X64976Y-126000D01*
X62977Y-123001D02*
X62477Y-122501D01*
Y-121501D01*
X62977Y-121001D01*
X63477D01*
X63976Y-121501D01*
X64476Y-121001D01*
X64976D01*
X65476Y-121501D01*
Y-122501D01*
X64976Y-123001D01*
X64476D01*
X63976Y-122501D01*
X63477Y-123001D01*
X62977D01*
X63976Y-122501D02*
Y-121501D01*
X499000Y-124883D02*
X498500Y-125383D01*
Y-126382D01*
X499000Y-126882D01*
X501000D01*
X501500Y-126382D01*
Y-125383D01*
X501000Y-124883D01*
X499000Y-123883D02*
X498500Y-123383D01*
Y-122384D01*
X499000Y-121884D01*
X499500D01*
X500000Y-122384D01*
Y-122883D01*
Y-122384D01*
X500500Y-121884D01*
X501000D01*
X501500Y-122384D01*
Y-123383D01*
X501000Y-123883D01*
X499000Y-120884D02*
X498500Y-120384D01*
Y-119385D01*
X499000Y-118885D01*
X499500D01*
X500000Y-119385D01*
Y-119884D01*
Y-119385D01*
X500500Y-118885D01*
X501000D01*
X501500Y-119385D01*
Y-120384D01*
X501000Y-120884D01*
X469457Y-136648D02*
X468958Y-136148D01*
X467958D01*
X467458Y-136648D01*
Y-138647D01*
X467958Y-139147D01*
X468958D01*
X469457Y-138647D01*
X470457Y-136648D02*
X470957Y-136148D01*
X471956D01*
X472456Y-136648D01*
Y-137147D01*
X471956Y-137647D01*
X471457D01*
X471956D01*
X472456Y-138147D01*
Y-138647D01*
X471956Y-139147D01*
X470957D01*
X470457Y-138647D01*
X475455Y-139147D02*
X473456D01*
X475455Y-137147D01*
Y-136648D01*
X474956Y-136148D01*
X473956D01*
X473456Y-136648D01*
X444820Y-139147D02*
Y-136148D01*
X446320D01*
X446819Y-136648D01*
Y-137647D01*
X446320Y-138147D01*
X444820D01*
X445820D02*
X446819Y-139147D01*
X447819Y-136648D02*
X448319Y-136148D01*
X449319D01*
X449819Y-136648D01*
Y-137147D01*
X449319Y-137647D01*
X448819D01*
X449319D01*
X449819Y-138147D01*
Y-138647D01*
X449319Y-139147D01*
X448319D01*
X447819Y-138647D01*
X450818Y-136148D02*
X452818D01*
Y-136648D01*
X450818Y-138647D01*
Y-139147D01*
X392191Y-102137D02*
X394690D01*
X395190Y-101638D01*
Y-100638D01*
X394690Y-100138D01*
X392191D01*
X395190Y-99138D02*
Y-98139D01*
Y-98639D01*
X392191D01*
X392691Y-99138D01*
X392191Y-94640D02*
Y-96639D01*
X393691D01*
X393191Y-95639D01*
Y-95140D01*
X393691Y-94640D01*
X394690D01*
X395190Y-95140D01*
Y-96139D01*
X394690Y-96639D01*
X632843Y-50033D02*
X632343Y-49534D01*
X631344D01*
X630844Y-50033D01*
Y-52033D01*
X631344Y-52533D01*
X632343D01*
X632843Y-52033D01*
X633843Y-50033D02*
X634343Y-49534D01*
X635342D01*
X635842Y-50033D01*
Y-50533D01*
X635342Y-51033D01*
X634842D01*
X635342D01*
X635842Y-51533D01*
Y-52033D01*
X635342Y-52533D01*
X634343D01*
X633843Y-52033D01*
X636842Y-49534D02*
X638841D01*
Y-50033D01*
X636842Y-52033D01*
Y-52533D01*
X598394Y-12632D02*
X597894Y-12132D01*
X596895D01*
X596395Y-12632D01*
Y-14631D01*
X596895Y-15131D01*
X597894D01*
X598394Y-14631D01*
X599394Y-12632D02*
X599894Y-12132D01*
X600894D01*
X601393Y-12632D01*
Y-13132D01*
X600894Y-13632D01*
X600394D01*
X600894D01*
X601393Y-14131D01*
Y-14631D01*
X600894Y-15131D01*
X599894D01*
X599394Y-14631D01*
X604392Y-12132D02*
X603393Y-12632D01*
X602393Y-13632D01*
Y-14631D01*
X602893Y-15131D01*
X603893D01*
X604392Y-14631D01*
Y-14131D01*
X603893Y-13632D01*
X602393D01*
X632843Y-57907D02*
X632343Y-57408D01*
X631344D01*
X630844Y-57907D01*
Y-59907D01*
X631344Y-60407D01*
X632343D01*
X632843Y-59907D01*
X633843Y-57907D02*
X634343Y-57408D01*
X635342D01*
X635842Y-57907D01*
Y-58407D01*
X635342Y-58907D01*
X634842D01*
X635342D01*
X635842Y-59407D01*
Y-59907D01*
X635342Y-60407D01*
X634343D01*
X633843Y-59907D01*
X638841Y-57408D02*
X636842D01*
Y-58907D01*
X637842Y-58407D01*
X638341D01*
X638841Y-58907D01*
Y-59907D01*
X638341Y-60407D01*
X637342D01*
X636842Y-59907D01*
X598394Y-20506D02*
X597894Y-20006D01*
X596895D01*
X596395Y-20506D01*
Y-22505D01*
X596895Y-23005D01*
X597894D01*
X598394Y-22505D01*
X599394Y-20506D02*
X599894Y-20006D01*
X600894D01*
X601393Y-20506D01*
Y-21006D01*
X600894Y-21506D01*
X600394D01*
X600894D01*
X601393Y-22005D01*
Y-22505D01*
X600894Y-23005D01*
X599894D01*
X599394Y-22505D01*
X603893Y-23005D02*
Y-20006D01*
X602393Y-21506D01*
X604392D01*
X35690Y-297319D02*
Y-300318D01*
X37189D01*
X37689Y-299819D01*
Y-297819D01*
X37189Y-297319D01*
X35690D01*
X40688Y-300318D02*
X38689D01*
X40688Y-298319D01*
Y-297819D01*
X40188Y-297319D01*
X39189D01*
X38689Y-297819D01*
X37371Y-189052D02*
Y-192051D01*
X38870D01*
X39370Y-191551D01*
Y-189551D01*
X38870Y-189052D01*
X37371D01*
X40370Y-192051D02*
X41369D01*
X40870D01*
Y-189052D01*
X40370Y-189551D01*
X401106Y-123929D02*
X398107D01*
Y-122430D01*
X398607Y-121930D01*
X399606D01*
X400106Y-122430D01*
Y-123929D01*
Y-122930D02*
X401106Y-121930D01*
Y-118931D02*
Y-120930D01*
X399106Y-118931D01*
X398607D01*
X398107Y-119431D01*
Y-120431D01*
X398607Y-120930D01*
X398107Y-117931D02*
Y-115932D01*
X398607D01*
X400606Y-117931D01*
X401106D01*
X407125Y-124248D02*
X404126D01*
Y-122749D01*
X404626Y-122249D01*
X405625D01*
X406125Y-122749D01*
Y-124248D01*
Y-123249D02*
X407125Y-122249D01*
Y-119250D02*
Y-121249D01*
X405126Y-119250D01*
X404626D01*
X404126Y-119750D01*
Y-120749D01*
X404626Y-121249D01*
X404126Y-116251D02*
X404626Y-117251D01*
X405625Y-118250D01*
X406625D01*
X407125Y-117750D01*
Y-116751D01*
X406625Y-116251D01*
X406125D01*
X405625Y-116751D01*
Y-118250D01*
X309637Y-131571D02*
Y-134071D01*
X310137Y-134570D01*
X311137D01*
X311636Y-134071D01*
Y-131571D01*
X312636Y-134570D02*
X313636D01*
X313136D01*
Y-131571D01*
X312636Y-132071D01*
X315135D02*
X315635Y-131571D01*
X316635D01*
X317135Y-132071D01*
Y-134071D01*
X316635Y-134570D01*
X315635D01*
X315135Y-134071D01*
Y-132071D01*
X84177Y-187804D02*
X81178D01*
Y-186304D01*
X81678Y-185804D01*
X82677D01*
X83177Y-186304D01*
Y-187804D01*
Y-186804D02*
X84177Y-185804D01*
Y-184805D02*
Y-183805D01*
Y-184305D01*
X81178D01*
X81678Y-184805D01*
X84177Y-180806D02*
X81178D01*
X82677Y-182306D01*
Y-180306D01*
X509047Y-134179D02*
Y-136678D01*
X509546Y-137178D01*
X510546D01*
X511046Y-136678D01*
Y-134179D01*
X512045Y-137178D02*
X513045D01*
X512545D01*
Y-134179D01*
X512045Y-134679D01*
X516044Y-137178D02*
Y-134179D01*
X514545Y-135679D01*
X516544D01*
X478535Y-112526D02*
Y-115025D01*
X479035Y-115525D01*
X480034D01*
X480534Y-115025D01*
Y-112526D01*
X481534Y-115525D02*
X482533D01*
X482034D01*
Y-112526D01*
X481534Y-113025D01*
X484033D02*
X484533Y-112526D01*
X485532D01*
X486032Y-113025D01*
Y-113525D01*
X485532Y-114025D01*
X485033D01*
X485532D01*
X486032Y-114525D01*
Y-115025D01*
X485532Y-115525D01*
X484533D01*
X484033Y-115025D01*
X223485Y-107949D02*
Y-110449D01*
X223985Y-110948D01*
X224985D01*
X225484Y-110449D01*
Y-107949D01*
X227984Y-110948D02*
Y-107949D01*
X226484Y-109449D01*
X228483D01*
X293564Y-108737D02*
Y-111236D01*
X294064Y-111736D01*
X295063D01*
X295563Y-111236D01*
Y-108737D01*
X296563Y-109237D02*
X297063Y-108737D01*
X298062D01*
X298562Y-109237D01*
Y-109736D01*
X298062Y-110236D01*
X297563D01*
X298062D01*
X298562Y-110736D01*
Y-111236D01*
X298062Y-111736D01*
X297063D01*
X296563Y-111236D01*
X53088Y-154059D02*
Y-151059D01*
X54587D01*
X55087Y-151559D01*
Y-152559D01*
X54587Y-153059D01*
X53088D01*
X54088D02*
X55087Y-154059D01*
X58086D02*
X56087D01*
X58086Y-152059D01*
Y-151559D01*
X57586Y-151059D01*
X56587D01*
X56087Y-151559D01*
X61085Y-151059D02*
X59086D01*
Y-152559D01*
X60086Y-152059D01*
X60585D01*
X61085Y-152559D01*
Y-153559D01*
X60585Y-154059D01*
X59586D01*
X59086Y-153559D01*
X77287Y-294103D02*
X74288D01*
Y-292604D01*
X74788Y-292104D01*
X75787D01*
X76287Y-292604D01*
Y-294103D01*
Y-293103D02*
X77287Y-292104D01*
Y-291104D02*
Y-290104D01*
Y-290604D01*
X74288D01*
X74788Y-291104D01*
X74288Y-288605D02*
Y-286606D01*
X74788D01*
X76787Y-288605D01*
X77287D01*
X235902Y-109243D02*
X238901D01*
Y-110743D01*
X238401Y-111243D01*
X237402D01*
X236902Y-110743D01*
Y-109243D01*
Y-110243D02*
X235902Y-111243D01*
Y-112242D02*
Y-113242D01*
Y-112742D01*
X238901D01*
X238401Y-112242D01*
Y-114742D02*
X238901Y-115241D01*
Y-116241D01*
X238401Y-116741D01*
X237901D01*
X237402Y-116241D01*
Y-115741D01*
Y-116241D01*
X236902Y-116741D01*
X236402D01*
X235902Y-116241D01*
Y-115241D01*
X236402Y-114742D01*
X201303Y-130569D02*
X198304D01*
Y-129070D01*
X198803Y-128570D01*
X199803D01*
X200303Y-129070D01*
Y-130569D01*
Y-129570D02*
X201303Y-128570D01*
Y-127570D02*
Y-126570D01*
Y-127070D01*
X198304D01*
X198803Y-127570D01*
X201303Y-123072D02*
Y-125071D01*
X199303Y-123072D01*
X198803D01*
X198304Y-123572D01*
Y-124571D01*
X198803Y-125071D01*
X253444Y-128271D02*
Y-125272D01*
X254943D01*
X255443Y-125772D01*
Y-126772D01*
X254943Y-127271D01*
X253444D01*
X254444D02*
X255443Y-128271D01*
X256443D02*
X257443D01*
X256943D01*
Y-125272D01*
X256443Y-125772D01*
X258942Y-128271D02*
X259942D01*
X259442D01*
Y-125272D01*
X258942Y-125772D01*
X252157Y-120397D02*
Y-117398D01*
X253656D01*
X254156Y-117898D01*
Y-118898D01*
X253656Y-119397D01*
X252157D01*
X253156D02*
X254156Y-120397D01*
X255156D02*
X256155D01*
X255656D01*
Y-117398D01*
X255156Y-117898D01*
X257655D02*
X258155Y-117398D01*
X259155D01*
X259654Y-117898D01*
Y-119897D01*
X259155Y-120397D01*
X258155D01*
X257655Y-119897D01*
Y-117898D01*
X527544Y-127926D02*
X527044Y-128426D01*
Y-129426D01*
X527544Y-129926D01*
X529543D01*
X530043Y-129426D01*
Y-128426D01*
X529543Y-127926D01*
X527544Y-126927D02*
X527044Y-126427D01*
Y-125427D01*
X527544Y-124927D01*
X528044D01*
X528543Y-125427D01*
Y-125927D01*
Y-125427D01*
X529043Y-124927D01*
X529543D01*
X530043Y-125427D01*
Y-126427D01*
X529543Y-126927D01*
X530043Y-123928D02*
Y-122928D01*
Y-123428D01*
X527044D01*
X527544Y-123928D01*
X501938Y-111057D02*
X501438Y-110557D01*
X500438D01*
X499938Y-111057D01*
Y-113056D01*
X500438Y-113556D01*
X501438D01*
X501938Y-113056D01*
X502937Y-111057D02*
X503437Y-110557D01*
X504437D01*
X504937Y-111057D01*
Y-111557D01*
X504437Y-112057D01*
X503937D01*
X504437D01*
X504937Y-112557D01*
Y-113056D01*
X504437Y-113556D01*
X503437D01*
X502937Y-113056D01*
X505936Y-111057D02*
X506436Y-110557D01*
X507436D01*
X507936Y-111057D01*
Y-113056D01*
X507436Y-113556D01*
X506436D01*
X505936Y-113056D01*
Y-111057D01*
X66914Y-346487D02*
X66414Y-346987D01*
Y-347987D01*
X66914Y-348487D01*
X68913D01*
X69413Y-347987D01*
Y-346987D01*
X68913Y-346487D01*
X69413Y-343489D02*
Y-345488D01*
X67414Y-343489D01*
X66914D01*
X66414Y-343988D01*
Y-344988D01*
X66914Y-345488D01*
X68913Y-342489D02*
X69413Y-341989D01*
Y-340989D01*
X68913Y-340490D01*
X66914D01*
X66414Y-340989D01*
Y-341989D01*
X66914Y-342489D01*
X67414D01*
X67913Y-341989D01*
Y-340490D01*
X67898Y-238220D02*
X67398Y-238720D01*
Y-239719D01*
X67898Y-240219D01*
X69897D01*
X70397Y-239719D01*
Y-238720D01*
X69897Y-238220D01*
X70397Y-235221D02*
Y-237220D01*
X68398Y-235221D01*
X67898D01*
X67398Y-235721D01*
Y-236720D01*
X67898Y-237220D01*
Y-234221D02*
X67398Y-233721D01*
Y-232722D01*
X67898Y-232222D01*
X68398D01*
X68898Y-232722D01*
X69397Y-232222D01*
X69897D01*
X70397Y-232722D01*
Y-233721D01*
X69897Y-234221D01*
X69397D01*
X68898Y-233721D01*
X68398Y-234221D01*
X67898D01*
X68898Y-233721D02*
Y-232722D01*
X67898Y-292354D02*
X67398Y-292853D01*
Y-293853D01*
X67898Y-294353D01*
X69897D01*
X70397Y-293853D01*
Y-292853D01*
X69897Y-292354D01*
X70397Y-289355D02*
Y-291354D01*
X68398Y-289355D01*
X67898D01*
X67398Y-289855D01*
Y-290854D01*
X67898Y-291354D01*
X67398Y-288355D02*
Y-286356D01*
X67898D01*
X69897Y-288355D01*
X70397D01*
X66914Y-186055D02*
X66414Y-186554D01*
Y-187554D01*
X66914Y-188054D01*
X68913D01*
X69413Y-187554D01*
Y-186554D01*
X68913Y-186055D01*
X69413Y-183055D02*
Y-185055D01*
X67414Y-183055D01*
X66914D01*
X66414Y-183555D01*
Y-184555D01*
X66914Y-185055D01*
X66414Y-180056D02*
X66914Y-181056D01*
X67913Y-182056D01*
X68913D01*
X69413Y-181556D01*
Y-180556D01*
X68913Y-180056D01*
X68413D01*
X67913Y-180556D01*
Y-182056D01*
X250212Y-113749D02*
X250712Y-113249D01*
Y-112249D01*
X250212Y-111749D01*
X248213D01*
X247713Y-112249D01*
Y-113249D01*
X248213Y-113749D01*
X247713Y-116748D02*
Y-114748D01*
X249712Y-116748D01*
X250212D01*
X250712Y-116248D01*
Y-115248D01*
X250212Y-114748D01*
X247713Y-119247D02*
X250712D01*
X249213Y-117747D01*
Y-119747D01*
X255481Y-110418D02*
X254981Y-109918D01*
X253981D01*
X253482Y-110418D01*
Y-112417D01*
X253981Y-112917D01*
X254981D01*
X255481Y-112417D01*
X258480Y-112917D02*
X256481D01*
X258480Y-110917D01*
Y-110418D01*
X257980Y-109918D01*
X256980D01*
X256481Y-110418D01*
X259480D02*
X259980Y-109918D01*
X260979D01*
X261479Y-110418D01*
Y-110917D01*
X260979Y-111417D01*
X260479D01*
X260979D01*
X261479Y-111917D01*
Y-112417D01*
X260979Y-112917D01*
X259980D01*
X259480Y-112417D01*
X14764Y-146653D02*
X12764D01*
X11765Y-145654D01*
X12764Y-144654D01*
X14764D01*
X13264D01*
Y-146653D01*
X14764Y-143655D02*
X11765D01*
X14764Y-141655D01*
X11765D01*
X14764Y-140656D02*
Y-139656D01*
Y-140156D01*
X11765D01*
X12265Y-140656D01*
X14465Y-253724D02*
X12465D01*
X11466Y-252725D01*
X12465Y-251725D01*
X14465D01*
X12965D01*
Y-253724D01*
X14465Y-250725D02*
X11466D01*
X14465Y-248726D01*
X11466D01*
X11965Y-247726D02*
X11466Y-247227D01*
Y-246227D01*
X11965Y-245727D01*
X12465D01*
X12965Y-246227D01*
Y-246727D01*
Y-246227D01*
X13465Y-245727D01*
X13965D01*
X14465Y-246227D01*
Y-247227D01*
X13965Y-247726D01*
X14465Y-200437D02*
X12465D01*
X11466Y-199437D01*
X12465Y-198438D01*
X14465D01*
X12965D01*
Y-200437D01*
X14465Y-197438D02*
X11466D01*
X14465Y-195439D01*
X11466D01*
X14465Y-192440D02*
Y-194439D01*
X12465Y-192440D01*
X11965D01*
X11466Y-192939D01*
Y-193939D01*
X11965Y-194439D01*
X14071Y-305813D02*
X12071D01*
X11072Y-304813D01*
X12071Y-303813D01*
X14071D01*
X12571D01*
Y-305813D01*
X14071Y-302814D02*
X11072D01*
X14071Y-300814D01*
X11072D01*
X14071Y-298315D02*
X11072D01*
X12571Y-299815D01*
Y-297815D01*
X454194Y-113510D02*
Y-116009D01*
X454694Y-116509D01*
X455693D01*
X456193Y-116009D01*
Y-113510D01*
X457193D02*
X459192D01*
Y-114010D01*
X457193Y-116009D01*
Y-116509D01*
X445835Y-114010D02*
X445335Y-113510D01*
X444336D01*
X443836Y-114010D01*
Y-116009D01*
X444336Y-116509D01*
X445335D01*
X445835Y-116009D01*
X448834Y-116509D02*
X446835D01*
X448834Y-114510D01*
Y-114010D01*
X448335Y-113510D01*
X447335D01*
X446835Y-114010D01*
X451833Y-113510D02*
X449834D01*
Y-115009D01*
X450834Y-114510D01*
X451334D01*
X451833Y-115009D01*
Y-116009D01*
X451334Y-116509D01*
X450334D01*
X449834Y-116009D01*
X85161Y-294103D02*
X82162D01*
Y-292604D01*
X82662Y-292104D01*
X83661D01*
X84161Y-292604D01*
Y-294103D01*
Y-293103D02*
X85161Y-292104D01*
Y-291104D02*
Y-290104D01*
Y-290604D01*
X82162D01*
X82662Y-291104D01*
X82162Y-286606D02*
X82662Y-287605D01*
X83661Y-288605D01*
X84661D01*
X85161Y-288105D01*
Y-287105D01*
X84661Y-286606D01*
X84161D01*
X83661Y-287105D01*
Y-288605D01*
X76303Y-187804D02*
X73304D01*
Y-186304D01*
X73804Y-185804D01*
X74803D01*
X75303Y-186304D01*
Y-187804D01*
Y-186804D02*
X76303Y-185804D01*
Y-184805D02*
Y-183805D01*
Y-184305D01*
X73304D01*
X73804Y-184805D01*
X73304Y-180306D02*
Y-182306D01*
X74803D01*
X74303Y-181306D01*
Y-180806D01*
X74803Y-180306D01*
X75803D01*
X76303Y-180806D01*
Y-181806D01*
X75803Y-182306D01*
X580266Y-118405D02*
Y-115407D01*
X581766D01*
X582266Y-115906D01*
Y-116906D01*
X581766Y-117406D01*
X580266D01*
X581266D02*
X582266Y-118405D01*
X585264Y-115407D02*
X583265D01*
Y-116906D01*
X584265Y-116406D01*
X584765D01*
X585264Y-116906D01*
Y-117906D01*
X584765Y-118405D01*
X583765D01*
X583265Y-117906D01*
X80315Y-37158D02*
Y-39658D01*
X80815Y-40157D01*
X81814D01*
X82314Y-39658D01*
Y-37158D01*
X83314Y-39658D02*
X83814Y-40157D01*
X84813D01*
X85313Y-39658D01*
Y-37658D01*
X84813Y-37158D01*
X83814D01*
X83314Y-37658D01*
Y-38158D01*
X83814Y-38658D01*
X85313D01*
X551575Y-306450D02*
Y-308949D01*
X552075Y-309449D01*
X553074D01*
X553574Y-308949D01*
Y-306450D01*
X556573D02*
X554574D01*
Y-307949D01*
X555574Y-307450D01*
X556073D01*
X556573Y-307949D01*
Y-308949D01*
X556073Y-309449D01*
X555074D01*
X554574Y-308949D01*
X553763Y-106257D02*
X551264D01*
X550764Y-106757D01*
Y-107756D01*
X551264Y-108256D01*
X553763D01*
X550764Y-111255D02*
Y-109256D01*
X552764Y-111255D01*
X553263D01*
X553763Y-110755D01*
Y-109756D01*
X553263Y-109256D01*
X554088Y-250000D02*
X556587D01*
X557087Y-249500D01*
Y-248500D01*
X556587Y-248001D01*
X554088D01*
X557087Y-247001D02*
Y-246001D01*
Y-246501D01*
X554088D01*
X554587Y-247001D01*
X77756Y-240158D02*
X74757D01*
Y-238658D01*
X75257Y-238158D01*
X76256D01*
X76756Y-238658D01*
Y-240158D01*
Y-239158D02*
X77756Y-238158D01*
X75257Y-237158D02*
X74757Y-236659D01*
Y-235659D01*
X75257Y-235159D01*
X75757D01*
X76256Y-235659D01*
Y-236159D01*
Y-235659D01*
X76756Y-235159D01*
X77256D01*
X77756Y-235659D01*
Y-236659D01*
X77256Y-237158D01*
X75257Y-234159D02*
X74757Y-233660D01*
Y-232660D01*
X75257Y-232160D01*
X77256D01*
X77756Y-232660D01*
Y-233660D01*
X77256Y-234159D01*
X75257D01*
X84646Y-240158D02*
X81647D01*
Y-238658D01*
X82147Y-238158D01*
X83146D01*
X83646Y-238658D01*
Y-240158D01*
Y-239158D02*
X84646Y-238158D01*
Y-235159D02*
Y-237158D01*
X82646Y-235159D01*
X82147D01*
X81647Y-235659D01*
Y-236659D01*
X82147Y-237158D01*
X84146Y-234159D02*
X84646Y-233660D01*
Y-232660D01*
X84146Y-232160D01*
X82147D01*
X81647Y-232660D01*
Y-233660D01*
X82147Y-234159D01*
X82646D01*
X83146Y-233660D01*
Y-232160D01*
X54855Y-258220D02*
Y-255221D01*
X56355D01*
X56855Y-255721D01*
Y-256720D01*
X56355Y-257220D01*
X54855D01*
X55855D02*
X56855Y-258220D01*
X59854D02*
X57854D01*
X59854Y-256221D01*
Y-255721D01*
X59354Y-255221D01*
X58354D01*
X57854Y-255721D01*
X60853D02*
X61353Y-255221D01*
X62353D01*
X62853Y-255721D01*
Y-256221D01*
X62353Y-256720D01*
X62853Y-257220D01*
Y-257720D01*
X62353Y-258220D01*
X61353D01*
X60853Y-257720D01*
Y-257220D01*
X61353Y-256720D01*
X60853Y-256221D01*
Y-255721D01*
X61353Y-256720D02*
X62353D01*
X273118Y-361471D02*
X270119D01*
Y-359971D01*
X270619Y-359471D01*
X271618D01*
X272118Y-359971D01*
Y-361471D01*
Y-360471D02*
X273118Y-359471D01*
Y-356472D02*
Y-358471D01*
X271118Y-356472D01*
X270619D01*
X270119Y-356972D01*
Y-357972D01*
X270619Y-358471D01*
X273118Y-353973D02*
X270119D01*
X271618Y-355472D01*
Y-353473D01*
X218300Y-361171D02*
X215301D01*
Y-359671D01*
X215800Y-359171D01*
X216800D01*
X217300Y-359671D01*
Y-361171D01*
Y-360171D02*
X218300Y-359171D01*
Y-356172D02*
Y-358172D01*
X216300Y-356172D01*
X215800D01*
X215301Y-356672D01*
Y-357672D01*
X215800Y-358172D01*
Y-355172D02*
X215301Y-354673D01*
Y-353673D01*
X215800Y-353173D01*
X216300D01*
X216800Y-353673D01*
Y-354173D01*
Y-353673D01*
X217300Y-353173D01*
X217800D01*
X218300Y-353673D01*
Y-354673D01*
X217800Y-355172D01*
X109252Y-259695D02*
Y-256696D01*
X110751D01*
X111251Y-257195D01*
Y-258195D01*
X110751Y-258695D01*
X109252D01*
X110252D02*
X111251Y-259695D01*
X114250D02*
X112251D01*
X114250Y-257695D01*
Y-257195D01*
X113751Y-256696D01*
X112751D01*
X112251Y-257195D01*
X117249Y-259695D02*
X115250D01*
X117249Y-257695D01*
Y-257195D01*
X116750Y-256696D01*
X115750D01*
X115250Y-257195D01*
X642913Y-337992D02*
X645912D01*
Y-339492D01*
X645413Y-339991D01*
X644413D01*
X643913Y-339492D01*
Y-337992D01*
Y-338992D02*
X642913Y-339991D01*
Y-342990D02*
Y-340991D01*
X644913Y-342990D01*
X645413D01*
X645912Y-342491D01*
Y-341491D01*
X645413Y-340991D01*
X642913Y-343990D02*
Y-344990D01*
Y-344490D01*
X645912D01*
X645413Y-343990D01*
X661417Y-337795D02*
X664416D01*
Y-339295D01*
X663916Y-339795D01*
X662917D01*
X662417Y-339295D01*
Y-337795D01*
Y-338795D02*
X661417Y-339795D01*
Y-342794D02*
Y-340794D01*
X663417Y-342794D01*
X663916D01*
X664416Y-342294D01*
Y-341294D01*
X663916Y-340794D01*
Y-343793D02*
X664416Y-344293D01*
Y-345293D01*
X663916Y-345793D01*
X661917D01*
X661417Y-345293D01*
Y-344293D01*
X661917Y-343793D01*
X663916D01*
X531102Y-342520D02*
Y-339521D01*
X532602D01*
X533102Y-340020D01*
Y-341020D01*
X532602Y-341520D01*
X531102D01*
X532102D02*
X533102Y-342520D01*
X534101D02*
X535101D01*
X534601D01*
Y-339521D01*
X534101Y-340020D01*
X536601Y-342020D02*
X537100Y-342520D01*
X538100D01*
X538600Y-342020D01*
Y-340020D01*
X538100Y-339521D01*
X537100D01*
X536601Y-340020D01*
Y-340520D01*
X537100Y-341020D01*
X538600D01*
X533858Y-327165D02*
Y-324166D01*
X535358D01*
X535858Y-324666D01*
Y-325666D01*
X535358Y-326166D01*
X533858D01*
X534858D02*
X535858Y-327165D01*
X536857D02*
X537857D01*
X537357D01*
Y-324166D01*
X536857Y-324666D01*
X539357D02*
X539856Y-324166D01*
X540856D01*
X541356Y-324666D01*
Y-325166D01*
X540856Y-325666D01*
X541356Y-326166D01*
Y-326665D01*
X540856Y-327165D01*
X539856D01*
X539357Y-326665D01*
Y-326166D01*
X539856Y-325666D01*
X539357Y-325166D01*
Y-324666D01*
X539856Y-325666D02*
X540856D01*
X573483Y-106504D02*
Y-103505D01*
X574982D01*
X575482Y-104005D01*
Y-105004D01*
X574982Y-105504D01*
X573483D01*
X574482D02*
X575482Y-106504D01*
X576482Y-106004D02*
X576981Y-106504D01*
X577981D01*
X578481Y-106004D01*
Y-104005D01*
X577981Y-103505D01*
X576981D01*
X576482Y-104005D01*
Y-104505D01*
X576981Y-105004D01*
X578481D01*
X567568Y-205709D02*
Y-208708D01*
X566069D01*
X565569Y-208208D01*
Y-207208D01*
X566069Y-206708D01*
X567568D01*
X566569D02*
X565569Y-205709D01*
X564570Y-208208D02*
X564070Y-208708D01*
X563070D01*
X562570Y-208208D01*
Y-207708D01*
X563070Y-207208D01*
X562570Y-206708D01*
Y-206208D01*
X563070Y-205709D01*
X564070D01*
X564570Y-206208D01*
Y-206708D01*
X564070Y-207208D01*
X564570Y-207708D01*
Y-208208D01*
X564070Y-207208D02*
X563070D01*
X572758Y-123102D02*
X575757D01*
Y-124602D01*
X575257Y-125102D01*
X574258D01*
X573758Y-124602D01*
Y-123102D01*
Y-124102D02*
X572758Y-125102D01*
X575757Y-126101D02*
Y-128101D01*
X575257D01*
X573258Y-126101D01*
X572758D01*
X583033Y-243890D02*
X580034D01*
Y-242390D01*
X580534Y-241890D01*
X581534D01*
X582033Y-242390D01*
Y-243890D01*
Y-242890D02*
X583033Y-241890D01*
X580034Y-238891D02*
X580534Y-239891D01*
X581534Y-240891D01*
X582533D01*
X583033Y-240391D01*
Y-239391D01*
X582533Y-238891D01*
X582033D01*
X581534Y-239391D01*
Y-240891D01*
X589025Y-222342D02*
X586026D01*
Y-220843D01*
X586526Y-220343D01*
X587526D01*
X588026Y-220843D01*
Y-222342D01*
Y-221343D02*
X589025Y-220343D01*
Y-217844D02*
X586026D01*
X587526Y-219343D01*
Y-217344D01*
X532038Y-129724D02*
Y-126725D01*
X533537D01*
X534037Y-127225D01*
Y-128225D01*
X533537Y-128725D01*
X532038D01*
X533038D02*
X534037Y-129724D01*
X535037Y-127225D02*
X535537Y-126725D01*
X536536D01*
X537036Y-127225D01*
Y-127725D01*
X536536Y-128225D01*
X536036D01*
X536536D01*
X537036Y-128725D01*
Y-129225D01*
X536536Y-129724D01*
X535537D01*
X535037Y-129225D01*
X547638Y-228740D02*
Y-225741D01*
X549137D01*
X549637Y-226241D01*
Y-227241D01*
X549137Y-227741D01*
X547638D01*
X548637D02*
X549637Y-228740D01*
X552636D02*
X550637D01*
X552636Y-226741D01*
Y-226241D01*
X552136Y-225741D01*
X551137D01*
X550637Y-226241D01*
X630463Y-119488D02*
Y-116489D01*
X631962D01*
X632462Y-116989D01*
Y-117989D01*
X631962Y-118489D01*
X630463D01*
X631463D02*
X632462Y-119488D01*
X633462D02*
X634462D01*
X633962D01*
Y-116489D01*
X633462Y-116989D01*
X600394Y-199757D02*
Y-202756D01*
X602393D01*
X605392D02*
X603393D01*
X605392Y-200757D01*
Y-200257D01*
X604892Y-199757D01*
X603893D01*
X603393Y-200257D01*
X566535Y-278103D02*
Y-281102D01*
X568535D01*
X569534D02*
X570534D01*
X570034D01*
Y-278103D01*
X569534Y-278603D01*
X655936Y-243064D02*
X653937D01*
Y-244564D01*
X654937D01*
X653937D01*
Y-246063D01*
X656936D02*
X657936D01*
X657436D01*
Y-243064D01*
X656936Y-243564D01*
X-22684Y-126969D02*
X-19685D01*
Y-125469D01*
X-20185Y-124969D01*
X-22184D01*
X-22684Y-125469D01*
Y-126969D01*
X-19685Y-123969D02*
Y-122970D01*
Y-123470D01*
X-22684D01*
X-22184Y-123969D01*
X-19685Y-119971D02*
X-22684D01*
X-21185Y-121470D01*
Y-119471D01*
X-22684Y-83661D02*
X-19685D01*
Y-82162D01*
X-20185Y-81662D01*
X-22184D01*
X-22684Y-82162D01*
Y-83661D01*
X-19685Y-80662D02*
Y-79663D01*
Y-80163D01*
X-22684D01*
X-22184Y-80662D01*
Y-78163D02*
X-22684Y-77663D01*
Y-76664D01*
X-22184Y-76164D01*
X-21684D01*
X-21185Y-76664D01*
Y-77163D01*
Y-76664D01*
X-20685Y-76164D01*
X-20185D01*
X-19685Y-76664D01*
Y-77663D01*
X-20185Y-78163D01*
X45229Y-18701D02*
X48228D01*
Y-17201D01*
X47728Y-16701D01*
X45729D01*
X45229Y-17201D01*
Y-18701D01*
X48228Y-15702D02*
Y-14702D01*
Y-15202D01*
X45229D01*
X45729Y-15702D01*
X48228Y-13203D02*
Y-12203D01*
Y-12703D01*
X45229D01*
X45729Y-13203D01*
X642126Y-313930D02*
Y-316929D01*
X643625D01*
X644125Y-316429D01*
Y-314430D01*
X643625Y-313930D01*
X642126D01*
X645125Y-314430D02*
X645625Y-313930D01*
X646625D01*
X647124Y-314430D01*
Y-314930D01*
X646625Y-315430D01*
X647124Y-315929D01*
Y-316429D01*
X646625Y-316929D01*
X645625D01*
X645125Y-316429D01*
Y-315929D01*
X645625Y-315430D01*
X645125Y-314930D01*
Y-314430D01*
X645625Y-315430D02*
X646625D01*
X662205Y-314324D02*
Y-317323D01*
X663704D01*
X664204Y-316823D01*
Y-314824D01*
X663704Y-314324D01*
X662205D01*
X665204D02*
X667203D01*
Y-314824D01*
X665204Y-316823D01*
Y-317323D01*
X507087Y-340308D02*
Y-343307D01*
X508586D01*
X509086Y-342807D01*
Y-340808D01*
X508586Y-340308D01*
X507087D01*
X512085D02*
X511085Y-340808D01*
X510086Y-341808D01*
Y-342807D01*
X510585Y-343307D01*
X511585D01*
X512085Y-342807D01*
Y-342307D01*
X511585Y-341808D01*
X510086D01*
X506299Y-324560D02*
Y-327559D01*
X507799D01*
X508299Y-327059D01*
Y-325060D01*
X507799Y-324560D01*
X506299D01*
X511298D02*
X509298D01*
Y-326060D01*
X510298Y-325560D01*
X510798D01*
X511298Y-326060D01*
Y-327059D01*
X510798Y-327559D01*
X509798D01*
X509298Y-327059D01*
X628740Y-122591D02*
Y-125591D01*
X630240D01*
X630739Y-125091D01*
Y-123091D01*
X630240Y-122591D01*
X628740D01*
X633239Y-125591D02*
Y-122591D01*
X631739Y-124091D01*
X633739D01*
X339233Y-101938D02*
X338733Y-102437D01*
Y-103437D01*
X339233Y-103937D01*
X341232D01*
X341732Y-103437D01*
Y-102437D01*
X341232Y-101938D01*
X338733Y-98939D02*
X339233Y-99938D01*
X340233Y-100938D01*
X341232D01*
X341732Y-100438D01*
Y-99439D01*
X341232Y-98939D01*
X340733D01*
X340233Y-99439D01*
Y-100938D01*
X339233Y-97939D02*
X338733Y-97439D01*
Y-96439D01*
X339233Y-95940D01*
X339733D01*
X340233Y-96439D01*
Y-96939D01*
Y-96439D01*
X340733Y-95940D01*
X341232D01*
X341732Y-96439D01*
Y-97439D01*
X341232Y-97939D01*
X365885Y-97275D02*
X366385Y-96775D01*
Y-95775D01*
X365885Y-95276D01*
X363886D01*
X363386Y-95775D01*
Y-96775D01*
X363886Y-97275D01*
X366385Y-100274D02*
X365885Y-99274D01*
X364885Y-98275D01*
X363886D01*
X363386Y-98774D01*
Y-99774D01*
X363886Y-100274D01*
X364386D01*
X364885Y-99774D01*
Y-98275D01*
X363386Y-103273D02*
Y-101274D01*
X365385Y-103273D01*
X365885D01*
X366385Y-102773D01*
Y-101774D01*
X365885Y-101274D01*
X109705Y-98246D02*
X109206Y-98746D01*
Y-99746D01*
X109705Y-100246D01*
X111705D01*
X112205Y-99746D01*
Y-98746D01*
X111705Y-98246D01*
X109206Y-95247D02*
X109705Y-96247D01*
X110705Y-97247D01*
X111705D01*
X112205Y-96747D01*
Y-95747D01*
X111705Y-95247D01*
X111205D01*
X110705Y-95747D01*
Y-97247D01*
X112205Y-94248D02*
Y-93248D01*
Y-93748D01*
X109206D01*
X109705Y-94248D01*
X104784Y-98246D02*
X104284Y-98746D01*
Y-99746D01*
X104784Y-100246D01*
X106784D01*
X107283Y-99746D01*
Y-98746D01*
X106784Y-98246D01*
X104284Y-95247D02*
X104784Y-96247D01*
X105784Y-97247D01*
X106784D01*
X107283Y-96747D01*
Y-95747D01*
X106784Y-95247D01*
X106284D01*
X105784Y-95747D01*
Y-97247D01*
X104784Y-94248D02*
X104284Y-93748D01*
Y-92748D01*
X104784Y-92248D01*
X106784D01*
X107283Y-92748D01*
Y-93748D01*
X106784Y-94248D01*
X104784D01*
X116595Y-91357D02*
X116095Y-91856D01*
Y-92856D01*
X116595Y-93356D01*
X118595D01*
X119095Y-92856D01*
Y-91856D01*
X118595Y-91357D01*
X116095Y-88358D02*
Y-90357D01*
X117595D01*
X117095Y-89357D01*
Y-88857D01*
X117595Y-88358D01*
X118595D01*
X119095Y-88857D01*
Y-89857D01*
X118595Y-90357D01*
Y-87358D02*
X119095Y-86858D01*
Y-85858D01*
X118595Y-85359D01*
X116595D01*
X116095Y-85858D01*
Y-86858D01*
X116595Y-87358D01*
X117095D01*
X117595Y-86858D01*
Y-85359D01*
X123485Y-91357D02*
X122985Y-91856D01*
Y-92856D01*
X123485Y-93356D01*
X125484D01*
X125984Y-92856D01*
Y-91856D01*
X125484Y-91357D01*
X122985Y-88358D02*
Y-90357D01*
X124485D01*
X123985Y-89357D01*
Y-88857D01*
X124485Y-88358D01*
X125484D01*
X125984Y-88857D01*
Y-89857D01*
X125484Y-90357D01*
X123485Y-87358D02*
X122985Y-86858D01*
Y-85858D01*
X123485Y-85359D01*
X123985D01*
X124485Y-85858D01*
X124985Y-85359D01*
X125484D01*
X125984Y-85858D01*
Y-86858D01*
X125484Y-87358D01*
X124985D01*
X124485Y-86858D01*
X123985Y-87358D01*
X123485D01*
X124485Y-86858D02*
Y-85858D01*
X571636Y-110099D02*
X571136Y-109599D01*
X570136D01*
X569636Y-110099D01*
Y-112099D01*
X570136Y-112598D01*
X571136D01*
X571636Y-112099D01*
X574635Y-112598D02*
X572635D01*
X574635Y-110599D01*
Y-110099D01*
X574135Y-109599D01*
X573135D01*
X572635Y-110099D01*
X577634Y-112598D02*
X575634D01*
X577634Y-110599D01*
Y-110099D01*
X577134Y-109599D01*
X576134D01*
X575634Y-110099D01*
X545561Y-102196D02*
X546060Y-101696D01*
Y-100697D01*
X545561Y-100197D01*
X543561D01*
X543061Y-100697D01*
Y-101696D01*
X543561Y-102196D01*
X543061Y-105195D02*
Y-103196D01*
X545061Y-105195D01*
X545561D01*
X546060Y-104695D01*
Y-103696D01*
X545561Y-103196D01*
X543061Y-106195D02*
Y-107195D01*
Y-106695D01*
X546060D01*
X545561Y-106195D01*
X566160Y-214409D02*
X566659Y-214909D01*
X567659D01*
X568159Y-214409D01*
Y-212409D01*
X567659Y-211910D01*
X566659D01*
X566160Y-212409D01*
X563161Y-211910D02*
X565160D01*
X563161Y-213909D01*
Y-214409D01*
X563660Y-214909D01*
X564660D01*
X565160Y-214409D01*
X562161D02*
X561661Y-214909D01*
X560662D01*
X560162Y-214409D01*
Y-212409D01*
X560662Y-211910D01*
X561661D01*
X562161Y-212409D01*
Y-214409D01*
X547057Y-221524D02*
X546558Y-222024D01*
Y-223024D01*
X547057Y-223524D01*
X549057D01*
X549557Y-223024D01*
Y-222024D01*
X549057Y-221524D01*
X549557Y-220525D02*
Y-219525D01*
Y-220025D01*
X546558D01*
X547057Y-220525D01*
X549057Y-218025D02*
X549557Y-217526D01*
Y-216526D01*
X549057Y-216026D01*
X547057D01*
X546558Y-216526D01*
Y-217526D01*
X547057Y-218025D01*
X547557D01*
X548057Y-217526D01*
Y-216026D01*
X587117Y-232056D02*
X586617Y-232556D01*
Y-233555D01*
X587117Y-234055D01*
X589116D01*
X589616Y-233555D01*
Y-232556D01*
X589116Y-232056D01*
X589616Y-231056D02*
Y-230056D01*
Y-230556D01*
X586617D01*
X587117Y-231056D01*
Y-228557D02*
X586617Y-228057D01*
Y-227057D01*
X587117Y-226557D01*
X587616D01*
X588116Y-227057D01*
X588616Y-226557D01*
X589116D01*
X589616Y-227057D01*
Y-228057D01*
X589116Y-228557D01*
X588616D01*
X588116Y-228057D01*
X587616Y-228557D01*
X587117D01*
X588116Y-228057D02*
Y-227057D01*
X591841Y-232056D02*
X591341Y-232556D01*
Y-233555D01*
X591841Y-234055D01*
X593840D01*
X594340Y-233555D01*
Y-232556D01*
X593840Y-232056D01*
X594340Y-231056D02*
Y-230056D01*
Y-230556D01*
X591341D01*
X591841Y-231056D01*
X591341Y-228557D02*
Y-226557D01*
X591841D01*
X593840Y-228557D01*
X594340D01*
X596565Y-232056D02*
X596066Y-232556D01*
Y-233555D01*
X596565Y-234055D01*
X598565D01*
X599065Y-233555D01*
Y-232556D01*
X598565Y-232056D01*
X599065Y-231056D02*
Y-230056D01*
Y-230556D01*
X596066D01*
X596565Y-231056D01*
X596066Y-226557D02*
X596565Y-227557D01*
X597565Y-228557D01*
X598565D01*
X599065Y-228057D01*
Y-227057D01*
X598565Y-226557D01*
X598065D01*
X597565Y-227057D01*
Y-228557D01*
X601684Y-232056D02*
X601184Y-232556D01*
Y-233555D01*
X601684Y-234055D01*
X603683D01*
X604183Y-233555D01*
Y-232556D01*
X603683Y-232056D01*
X604183Y-231056D02*
Y-230056D01*
Y-230556D01*
X601184D01*
X601684Y-231056D01*
X601184Y-226557D02*
Y-228557D01*
X602683D01*
X602183Y-227557D01*
Y-227057D01*
X602683Y-226557D01*
X603683D01*
X604183Y-227057D01*
Y-228057D01*
X603683Y-228557D01*
X614369Y-230629D02*
X613869Y-231129D01*
Y-232129D01*
X614369Y-232629D01*
X616368D01*
X616868Y-232129D01*
Y-231129D01*
X616368Y-230629D01*
X616868Y-229630D02*
Y-228630D01*
Y-229130D01*
X613869D01*
X614369Y-229630D01*
X616868Y-225631D02*
X613869D01*
X615369Y-227131D01*
Y-225131D01*
X621769Y-230729D02*
X621269Y-231229D01*
Y-232229D01*
X621769Y-232729D01*
X623768D01*
X624268Y-232229D01*
Y-231229D01*
X623768Y-230729D01*
X624268Y-229730D02*
Y-228730D01*
Y-229230D01*
X621269D01*
X621769Y-229730D01*
Y-227231D02*
X621269Y-226731D01*
Y-225731D01*
X621769Y-225231D01*
X622269D01*
X622769Y-225731D01*
Y-226231D01*
Y-225731D01*
X623269Y-225231D01*
X623768D01*
X624268Y-225731D01*
Y-226731D01*
X623768Y-227231D01*
X598316Y-124637D02*
X598816Y-124137D01*
Y-123138D01*
X598316Y-122638D01*
X596317D01*
X595817Y-123138D01*
Y-124137D01*
X596317Y-124637D01*
X595817Y-125637D02*
Y-126637D01*
Y-126137D01*
X598816D01*
X598316Y-125637D01*
X595817Y-130135D02*
Y-128136D01*
X597817Y-130135D01*
X598316D01*
X598816Y-129636D01*
Y-128636D01*
X598316Y-128136D01*
X593592Y-125031D02*
X594092Y-124531D01*
Y-123531D01*
X593592Y-123031D01*
X591593D01*
X591093Y-123531D01*
Y-124531D01*
X591593Y-125031D01*
X591093Y-126031D02*
Y-127030D01*
Y-126530D01*
X594092D01*
X593592Y-126031D01*
X591093Y-128530D02*
Y-129529D01*
Y-129030D01*
X594092D01*
X593592Y-128530D01*
X588080Y-125031D02*
X588580Y-124531D01*
Y-123531D01*
X588080Y-123031D01*
X586081D01*
X585581Y-123531D01*
Y-124531D01*
X586081Y-125031D01*
X585581Y-126031D02*
Y-127030D01*
Y-126530D01*
X588580D01*
X588080Y-126031D01*
Y-128530D02*
X588580Y-129030D01*
Y-130029D01*
X588080Y-130529D01*
X586081D01*
X585581Y-130029D01*
Y-129030D01*
X586081Y-128530D01*
X588080D01*
X602647Y-124637D02*
X603147Y-124137D01*
Y-123138D01*
X602647Y-122638D01*
X600648D01*
X600148Y-123138D01*
Y-124137D01*
X600648Y-124637D01*
Y-125637D02*
X600148Y-126137D01*
Y-127136D01*
X600648Y-127636D01*
X602647D01*
X603147Y-127136D01*
Y-126137D01*
X602647Y-125637D01*
X602147D01*
X601648Y-126137D01*
Y-127636D01*
X636793Y-139824D02*
X636293Y-139324D01*
X635293D01*
X634794Y-139824D01*
Y-141823D01*
X635293Y-142323D01*
X636293D01*
X636793Y-141823D01*
X637793Y-139824D02*
X638293Y-139324D01*
X639292D01*
X639792Y-139824D01*
Y-140323D01*
X639292Y-140823D01*
X639792Y-141323D01*
Y-141823D01*
X639292Y-142323D01*
X638293D01*
X637793Y-141823D01*
Y-141323D01*
X638293Y-140823D01*
X637793Y-140323D01*
Y-139824D01*
X638293Y-140823D02*
X639292D01*
X636793Y-131162D02*
X636293Y-130662D01*
X635293D01*
X634794Y-131162D01*
Y-133162D01*
X635293Y-133661D01*
X636293D01*
X636793Y-133162D01*
X637793Y-130662D02*
X639792D01*
Y-131162D01*
X637793Y-133162D01*
Y-133661D01*
X547607Y-249350D02*
X548107Y-249849D01*
X549107D01*
X549606Y-249350D01*
Y-247350D01*
X549107Y-246850D01*
X548107D01*
X547607Y-247350D01*
X544608Y-249849D02*
X545608Y-249350D01*
X546607Y-248350D01*
Y-247350D01*
X546107Y-246850D01*
X545108D01*
X544608Y-247350D01*
Y-247850D01*
X545108Y-248350D01*
X546607D01*
X530888Y-137461D02*
X530388Y-136962D01*
X529388D01*
X528888Y-137461D01*
Y-139461D01*
X529388Y-139961D01*
X530388D01*
X530888Y-139461D01*
X533887Y-136962D02*
X531887D01*
Y-138461D01*
X532887Y-137961D01*
X533387D01*
X533887Y-138461D01*
Y-139461D01*
X533387Y-139961D01*
X532387D01*
X531887Y-139461D01*
X565323Y-263129D02*
X565823Y-263629D01*
X566823D01*
X567323Y-263129D01*
Y-261130D01*
X566823Y-260630D01*
X565823D01*
X565323Y-261130D01*
X562824Y-260630D02*
Y-263629D01*
X564324Y-262129D01*
X562324D01*
X549287Y-143495D02*
X549786Y-142996D01*
Y-141996D01*
X549287Y-141496D01*
X547287D01*
X546787Y-141996D01*
Y-142996D01*
X547287Y-143495D01*
X549287Y-144495D02*
X549786Y-144995D01*
Y-145995D01*
X549287Y-146494D01*
X548787D01*
X548287Y-145995D01*
Y-145495D01*
Y-145995D01*
X547787Y-146494D01*
X547287D01*
X546787Y-145995D01*
Y-144995D01*
X547287Y-144495D01*
X638249Y-228119D02*
X637749Y-228619D01*
Y-229618D01*
X638249Y-230118D01*
X640248D01*
X640748Y-229618D01*
Y-228619D01*
X640248Y-228119D01*
X640748Y-225120D02*
Y-227119D01*
X638749Y-225120D01*
X638249D01*
X637749Y-225620D01*
Y-226619D01*
X638249Y-227119D01*
X646910Y-226938D02*
X646410Y-227437D01*
Y-228437D01*
X646910Y-228937D01*
X648910D01*
X649409Y-228437D01*
Y-227437D01*
X648910Y-226938D01*
X649409Y-225938D02*
Y-224938D01*
Y-225438D01*
X646410D01*
X646910Y-225938D01*
D23*
X10335Y-63927D02*
D03*
Y-108415D02*
D03*
D24*
X340551Y-56348D02*
D03*
X382874Y-31348D02*
D03*
D25*
X382874Y-71604D02*
D03*
X340551Y-16092D02*
D03*
M02*
